FILE_TYPE = MACRO_DRAWING;
SET COLOR_WIRE YELLOW;
SET COLOR_PROP MONO;
SET COLOR_DOT WHITE;
SET COLOR_ARC YELLOW;
SET COLOR_BODY GREEN;
SET COLOR_NOTE MONO;
SET PROP_DISPLAY VALUE;
SET PAGE_NUMBER P99;
FORCEADD PVCCIO_CPU0..1
(1900 5100);
FORCEPROP 3 LASTPIN (1900 5050) SIG_NAME PVCCIO_CPU0\g
J 0
(1910 5060);
DISPLAY 0.659574 (1910 5060);
PAINT MONO (1910 5060);
DISPLAY INVISIBLE (1910 5060);
FORCEPROP 1 LAST HDL_POWER PVCCIO_CPU0
J 1
(1900 5150);
DISPLAY 0.872340 (1900 5150);
PAINT GREEN (1900 5150);
DISPLAY INVISIBLE (1900 5150);
FORCEPROP 1 LAST BODY_TYPE PLUMBING
J 0
(1855 5057);
DISPLAY 0.340426 (1855 5057);
PAINT GREEN (1855 5057);
DISPLAY INVISIBLE (1855 5057);
FORCEPROP 1 LAST VOLTAGE 1.1V
J 0
(1855 5057);
DISPLAY 0.340426 (1855 5057);
PAINT SKYBLUE (1855 5057);
DISPLAY INVISIBLE (1855 5057);
FORCEPROP 2 LAST CDS_LIB mstr_symbols
J 0
(1900 5100);
PAINT ORANGE (1900 5100);
DISPLAY INVISIBLE (1900 5100);
FORCEPROP 1 LAST PATH I1
J 0
(1950 5125);
DISPLAY 0.872340 (1950 5125);
PAINT AQUA (1950 5125);
DISPLAY INVISIBLE (1950 5125);
FORCEADD RES..1
(1600 4300);
FORCEPROP 2 LASTPIN (1700 4300) SIG_NAME SMB_DDR_ABC_VPP_SDA
J 0
(1890 4310);
DISPLAY 0.617021 (1890 4310);
PAINT ORANGE (1890 4310);
FORCEPROP 1 LAST LOCATION R4T10
J 0
(1300 4250);
DISPLAY 0.617021 (1300 4250);
PAINT AQUA (1300 4250);
FORCEPROP 1 LAST PART_NUMBER G21796-173
J 0
(1625 4150);
DISPLAY 0.617021 (1625 4150);
PAINT BLUE (1625 4150);
FORCEPROP 1 LAST VALUE 20.0
J 2
(1550 4250);
DISPLAY 0.617021 (1550 4250);
PAINT SKYBLUE (1550 4250);
FORCEPROP 1 LAST TOLERANCE 1%
J 0
(1875 4250);
DISPLAY 0.617021 (1875 4250);
PAINT SKYBLUE (1875 4250);
FORCEPROP 1 LAST PACK_TYPE 0402
J 0
(1650 4250);
DISPLAY 0.617021 (1650 4250);
PAINT SKYBLUE (1650 4250);
FORCEPROP 1 LAST MATERIAL CHIP
J 0
(1800 4200);
DISPLAY 0.617021 (1800 4200);
PAINT SKYBLUE (1800 4200);
FORCEPROP 1 LAST WATTAGE 1/16W
J 2
(1775 4200);
DISPLAY 0.617021 (1775 4200);
PAINT SKYBLUE (1775 4200);
FORCEPROP 1 LASTPIN (1700 4300) $PN 2
J 0
(1662 4312);
DISPLAY 0.617021 (1662 4312);
PAINT MONO (1662 4312);
FORCEPROP 1 LASTPIN (1500 4300) $PN 1
J 0
(1512 4312);
DISPLAY 0.617021 (1512 4312);
PAINT MONO (1512 4312);
FORCEPROP 2 LAST CDS_LIB mstr_discrete
J 0
(1600 4300);
PAINT ORANGE (1600 4300);
DISPLAY INVISIBLE (1600 4300);
FORCEPROP 2 LAST CDS_SEC 1
J 0
(1550 4500);
DISPLAY 1.404255 (1550 4500);
PAINT ORANGE (1550 4500);
DISPLAY INVISIBLE (1550 4500);
FORCEPROP 2 LAST $SEC 1
J 0
(1550 4500);
DISPLAY 0.936170 (1550 4500);
PAINT MONO (1550 4500);
DISPLAY INVISIBLE (1550 4500);
FORCEPROP 2 LAST CDS_LOCATION R4T10
J 0
(1300 4250);
DISPLAY 0.617021 (1300 4250);
PAINT AQUA (1300 4250);
DISPLAY INVISIBLE (1300 4250);
FORCEPROP 1 LAST PATH I10
J 0
(1550 4450);
DISPLAY 0.978723 (1550 4450);
PAINT WHITE (1550 4450);
DISPLAY INVISIBLE (1550 4450);
FORCEPROP 2 LAST ROOM MEM
J 0
(1800 4300);
DISPLAY 1.404255 (1800 4300);
PAINT ORANGE (1800 4300);
DISPLAY INVISIBLE (1800 4300);
FORCEADD OFFPAGE..6
(-2400 900);
FORCEPROP 2 LAST $XR0 55 
J 0
(-2649 900);
DISPLAY 0.638298 (-2649 900);
PAINT MONO (-2649 900);
FORCEPROP 1 LAST COMMENT_BODY TRUE
J 0
(-2300 825);
DISPLAY 1.872340 (-2300 825);
PAINT GREEN (-2300 825);
DISPLAY INVISIBLE (-2300 825);
FORCEPROP 1 LAST OFFPAGE TRUE
J 0
(-2075 775);
PAINT GREEN (-2075 775);
DISPLAY INVISIBLE (-2075 775);
FORCEPROP 2 LAST BOM_COST SM_CONTROLLER
J 0
(-2625 950);
DISPLAY 1.617021 (-2625 950);
PAINT ORANGE (-2625 950);
DISPLAY INVISIBLE (-2625 950);
FORCEPROP 2 LAST CDS_LIB mstr_standard
J 0
(-2400 900);
PAINT MONO (-2400 900);
DISPLAY INVISIBLE (-2400 900);
FORCEPROP 2 LAST PATH I100
J 0
(-2625 950);
DISPLAY 1.021277 (-2625 950);
PAINT ORANGE (-2625 950);
DISPLAY INVISIBLE (-2625 950);
FORCEADD RES..2
(1275 3600);
FORCEPROP 1 LAST LOCATION R3R12
J 0
(1320 3725);
DISPLAY 0.617021 (1320 3725);
PAINT AQUA (1320 3725);
FORCEPROP 1 LAST PART_NUMBER G21796-235
J 0
(1315 3475);
DISPLAY 0.617021 (1315 3475);
PAINT BLUE (1315 3475);
FORCEPROP 1 LAST VALUE 665
J 0
(1320 3675);
DISPLAY 0.617021 (1320 3675);
PAINT SKYBLUE (1320 3675);
FORCEPROP 1 LAST TOLERANCE 1.0%
J 0
(1320 3625);
DISPLAY 0.617021 (1320 3625);
PAINT SKYBLUE (1320 3625);
FORCEPROP 1 LAST PACK_TYPE 0402
J 0
(1315 3425);
DISPLAY 0.617021 (1315 3425);
PAINT SKYBLUE (1315 3425);
FORCEPROP 1 LAST MATERIAL CHIP
J 0
(1315 3525);
DISPLAY 0.617021 (1315 3525);
PAINT SKYBLUE (1315 3525);
FORCEPROP 1 LAST WATTAGE 1/16W
J 0
(1315 3575);
DISPLAY 0.617021 (1315 3575);
PAINT SKYBLUE (1315 3575);
FORCEPROP 1 LASTPIN (1275 3500) $PN 2
J 0
(1280 3510);
DISPLAY 0.617021 (1280 3510);
PAINT MONO (1280 3510);
FORCEPROP 1 LASTPIN (1275 3700) $PN 1
J 0
(1280 3662);
DISPLAY 0.617021 (1280 3662);
PAINT MONO (1280 3662);
FORCEPROP 2 LAST CDS_LIB mstr_discrete
J 0
(1275 3600);
PAINT ORANGE (1275 3600);
DISPLAY INVISIBLE (1275 3600);
FORCEPROP 2 LAST BOM_COST SM_CONTROLLER
J 0
(1325 3775);
PAINT MONO (1325 3775);
DISPLAY INVISIBLE (1325 3775);
FORCEPROP 2 LAST SEC_TYPE 0402
J 0
(1325 3825);
DISPLAY 1.021277 (1325 3825);
PAINT ORANGE (1325 3825);
DISPLAY INVISIBLE (1325 3825);
FORCEPROP 2 LAST SEC 1
J 0
(1325 3825);
DISPLAY 0.936170 (1325 3825);
PAINT MONO (1325 3825);
DISPLAY INVISIBLE (1325 3825);
FORCEPROP 2 LAST CDS_LOCATION R3R12
J 0
(1320 3725);
DISPLAY 0.617021 (1320 3725);
PAINT AQUA (1320 3725);
DISPLAY INVISIBLE (1320 3725);
FORCEPROP 1 LAST PATH I101
J 0
(1325 3775);
DISPLAY 0.978723 (1325 3775);
PAINT WHITE (1325 3775);
DISPLAY INVISIBLE (1325 3775);
FORCEPROP 2 LAST ROOM MEM
J 0
(1325 3775);
PAINT MONO (1325 3775);
DISPLAY INVISIBLE (1325 3775);
FORCEADD PVPP_DEF..1
(925 3900);
FORCEPROP 3 LASTPIN (925 3850) SIG_NAME PVPP_DEF\g
J 0
(935 3860);
DISPLAY 0.659574 (935 3860);
PAINT MONO (935 3860);
DISPLAY INVISIBLE (935 3860);
FORCEPROP 1 LAST HDL_POWER PVPP_DEF
J 1
(925 3950);
DISPLAY 0.872340 (925 3950);
PAINT GREEN (925 3950);
DISPLAY INVISIBLE (925 3950);
FORCEPROP 1 LAST BODY_TYPE PLUMBING
J 0
(880 3857);
DISPLAY 0.340426 (880 3857);
PAINT GREEN (880 3857);
DISPLAY INVISIBLE (880 3857);
FORCEPROP 1 LAST VOLTAGE 2.5V
J 0
(880 3857);
DISPLAY 0.340426 (880 3857);
PAINT SKYBLUE (880 3857);
DISPLAY INVISIBLE (880 3857);
FORCEPROP 2 LAST BOM_COST SM_CONTROLLER
J 0
(925 4000);
DISPLAY 1.617021 (925 4000);
PAINT ORANGE (925 4000);
DISPLAY INVISIBLE (925 4000);
FORCEPROP 2 LAST CDS_LIB mstr_symbols
J 0
(925 3900);
PAINT ORANGE (925 3900);
DISPLAY INVISIBLE (925 3900);
FORCEPROP 1 LAST PATH I102
J 0
(975 3925);
DISPLAY 0.872340 (975 3925);
PAINT AQUA (975 3925);
DISPLAY INVISIBLE (975 3925);
FORCEPROP 2 LAST ROOM SMB
J 0
(925 3975);
PAINT MONO (925 3975);
DISPLAY INVISIBLE (925 3975);
FORCEADD RES..2
(925 3600);
FORCEPROP 1 LAST LOCATION R3R5
J 0
(970 3725);
DISPLAY 0.617021 (970 3725);
PAINT AQUA (970 3725);
FORCEPROP 1 LAST PART_NUMBER G21796-235
J 0
(965 3475);
DISPLAY 0.617021 (965 3475);
PAINT BLUE (965 3475);
FORCEPROP 1 LAST VALUE 665
J 0
(970 3675);
DISPLAY 0.617021 (970 3675);
PAINT SKYBLUE (970 3675);
FORCEPROP 1 LAST TOLERANCE 1.0%
J 0
(970 3625);
DISPLAY 0.617021 (970 3625);
PAINT SKYBLUE (970 3625);
FORCEPROP 1 LAST PACK_TYPE 0402
J 0
(965 3425);
DISPLAY 0.617021 (965 3425);
PAINT SKYBLUE (965 3425);
FORCEPROP 1 LAST MATERIAL CHIP
J 0
(965 3525);
DISPLAY 0.617021 (965 3525);
PAINT SKYBLUE (965 3525);
FORCEPROP 1 LAST WATTAGE 1/16W
J 0
(965 3575);
DISPLAY 0.617021 (965 3575);
PAINT SKYBLUE (965 3575);
FORCEPROP 1 LASTPIN (925 3500) $PN 2
J 0
(930 3510);
DISPLAY 0.617021 (930 3510);
PAINT MONO (930 3510);
FORCEPROP 1 LASTPIN (925 3700) $PN 1
J 0
(930 3662);
DISPLAY 0.617021 (930 3662);
PAINT MONO (930 3662);
FORCEPROP 2 LAST BOM_COST SM_CONTROLLER
J 0
(975 3775);
PAINT MONO (975 3775);
DISPLAY INVISIBLE (975 3775);
FORCEPROP 2 LAST CDS_LIB mstr_discrete
J 0
(925 3600);
PAINT ORANGE (925 3600);
DISPLAY INVISIBLE (925 3600);
FORCEPROP 2 LAST SEC_TYPE 0402
J 0
(975 3825);
DISPLAY 1.021277 (975 3825);
PAINT ORANGE (975 3825);
DISPLAY INVISIBLE (975 3825);
FORCEPROP 2 LAST SEC 1
J 0
(975 3825);
DISPLAY 0.936170 (975 3825);
PAINT MONO (975 3825);
DISPLAY INVISIBLE (975 3825);
FORCEPROP 2 LAST CDS_LOCATION R3R5
J 0
(970 3725);
DISPLAY 0.617021 (970 3725);
PAINT AQUA (970 3725);
DISPLAY INVISIBLE (970 3725);
FORCEPROP 1 LAST PATH I103
J 0
(975 3775);
DISPLAY 0.978723 (975 3775);
PAINT WHITE (975 3775);
DISPLAY INVISIBLE (975 3775);
FORCEPROP 2 LAST ROOM MEM
J 0
(975 3775);
PAINT MONO (975 3775);
DISPLAY INVISIBLE (975 3775);
FORCEADD RES..2
(1225 2450);
FORCEPROP 1 LAST LOCATION R6U18
J 0
(1270 2575);
DISPLAY 0.617021 (1270 2575);
PAINT AQUA (1270 2575);
FORCEPROP 1 LAST PART_NUMBER G21796-235
J 0
(1265 2325);
DISPLAY 0.617021 (1265 2325);
PAINT BLUE (1265 2325);
FORCEPROP 1 LAST VALUE 665
J 0
(1270 2525);
DISPLAY 0.617021 (1270 2525);
PAINT SKYBLUE (1270 2525);
FORCEPROP 1 LAST TOLERANCE 1.0%
J 0
(1270 2475);
DISPLAY 0.617021 (1270 2475);
PAINT SKYBLUE (1270 2475);
FORCEPROP 1 LAST PACK_TYPE 0402
J 0
(1265 2275);
DISPLAY 0.617021 (1265 2275);
PAINT SKYBLUE (1265 2275);
FORCEPROP 1 LAST MATERIAL CHIP
J 0
(1265 2375);
DISPLAY 0.617021 (1265 2375);
PAINT SKYBLUE (1265 2375);
FORCEPROP 1 LAST WATTAGE 1/16W
J 0
(1265 2425);
DISPLAY 0.617021 (1265 2425);
PAINT SKYBLUE (1265 2425);
FORCEPROP 1 LASTPIN (1225 2350) $PN 2
J 0
(1230 2360);
DISPLAY 0.617021 (1230 2360);
PAINT MONO (1230 2360);
FORCEPROP 1 LASTPIN (1225 2550) $PN 1
J 0
(1230 2512);
DISPLAY 0.617021 (1230 2512);
PAINT MONO (1230 2512);
FORCEPROP 2 LAST CDS_LIB mstr_discrete
J 0
(1225 2450);
PAINT ORANGE (1225 2450);
DISPLAY INVISIBLE (1225 2450);
FORCEPROP 2 LAST BOM_COST SM_CONTROLLER
J 0
(1275 2625);
PAINT MONO (1275 2625);
DISPLAY INVISIBLE (1275 2625);
FORCEPROP 2 LAST SEC_TYPE 0402
J 0
(1275 2675);
DISPLAY 1.021277 (1275 2675);
PAINT ORANGE (1275 2675);
DISPLAY INVISIBLE (1275 2675);
FORCEPROP 2 LAST SEC 1
J 0
(1275 2675);
DISPLAY 0.936170 (1275 2675);
PAINT MONO (1275 2675);
DISPLAY INVISIBLE (1275 2675);
FORCEPROP 2 LAST CDS_LOCATION R6U18
J 0
(1270 2575);
DISPLAY 0.617021 (1270 2575);
PAINT AQUA (1270 2575);
DISPLAY INVISIBLE (1270 2575);
FORCEPROP 1 LAST PATH I104
J 0
(1275 2625);
DISPLAY 0.978723 (1275 2625);
PAINT WHITE (1275 2625);
DISPLAY INVISIBLE (1275 2625);
FORCEPROP 2 LAST ROOM MEM
J 0
(1275 2625);
PAINT MONO (1275 2625);
DISPLAY INVISIBLE (1275 2625);
FORCEADD PVPP_GHJ..1
(875 2750);
FORCEPROP 3 LASTPIN (875 2700) SIG_NAME PVPP_GHJ\g
J 0
(885 2710);
DISPLAY 0.659574 (885 2710);
PAINT MONO (885 2710);
DISPLAY INVISIBLE (885 2710);
FORCEPROP 1 LAST HDL_POWER PVPP_GHJ
J 1
(875 2800);
DISPLAY 0.872340 (875 2800);
PAINT GREEN (875 2800);
DISPLAY INVISIBLE (875 2800);
FORCEPROP 1 LAST BODY_TYPE PLUMBING
J 0
(830 2707);
DISPLAY 0.340426 (830 2707);
PAINT GREEN (830 2707);
DISPLAY INVISIBLE (830 2707);
FORCEPROP 1 LAST VOLTAGE 2.5V
J 0
(830 2707);
DISPLAY 0.340426 (830 2707);
PAINT SKYBLUE (830 2707);
DISPLAY INVISIBLE (830 2707);
FORCEPROP 2 LAST BOM_COST SM_CONTROLLER
J 0
(875 2850);
DISPLAY 1.617021 (875 2850);
PAINT ORANGE (875 2850);
DISPLAY INVISIBLE (875 2850);
FORCEPROP 2 LAST CDS_LIB mstr_symbols
J 0
(875 2750);
PAINT ORANGE (875 2750);
DISPLAY INVISIBLE (875 2750);
FORCEPROP 1 LAST PATH I105
J 0
(925 2775);
DISPLAY 0.872340 (925 2775);
PAINT AQUA (925 2775);
DISPLAY INVISIBLE (925 2775);
FORCEPROP 2 LAST ROOM SMB
J 0
(875 2825);
PAINT MONO (875 2825);
DISPLAY INVISIBLE (875 2825);
FORCEADD RES..2
(875 2450);
FORCEPROP 1 LAST LOCATION R6U17
J 0
(920 2575);
DISPLAY 0.617021 (920 2575);
PAINT AQUA (920 2575);
FORCEPROP 1 LAST PART_NUMBER G21796-235
J 0
(915 2325);
DISPLAY 0.617021 (915 2325);
PAINT BLUE (915 2325);
FORCEPROP 1 LAST VALUE 665
J 0
(920 2525);
DISPLAY 0.617021 (920 2525);
PAINT SKYBLUE (920 2525);
FORCEPROP 1 LAST TOLERANCE 1.0%
J 0
(920 2475);
DISPLAY 0.617021 (920 2475);
PAINT SKYBLUE (920 2475);
FORCEPROP 1 LAST PACK_TYPE 0402
J 0
(915 2275);
DISPLAY 0.617021 (915 2275);
PAINT SKYBLUE (915 2275);
FORCEPROP 1 LAST MATERIAL CHIP
J 0
(915 2375);
DISPLAY 0.617021 (915 2375);
PAINT SKYBLUE (915 2375);
FORCEPROP 1 LAST WATTAGE 1/16W
J 0
(915 2425);
DISPLAY 0.617021 (915 2425);
PAINT SKYBLUE (915 2425);
FORCEPROP 1 LASTPIN (875 2350) $PN 2
J 0
(880 2360);
DISPLAY 0.617021 (880 2360);
PAINT MONO (880 2360);
FORCEPROP 1 LASTPIN (875 2550) $PN 1
J 0
(880 2512);
DISPLAY 0.617021 (880 2512);
PAINT MONO (880 2512);
FORCEPROP 2 LAST BOM_COST SM_CONTROLLER
J 0
(925 2625);
PAINT MONO (925 2625);
DISPLAY INVISIBLE (925 2625);
FORCEPROP 2 LAST CDS_LIB mstr_discrete
J 0
(875 2450);
PAINT ORANGE (875 2450);
DISPLAY INVISIBLE (875 2450);
FORCEPROP 2 LAST SEC_TYPE 0402
J 0
(925 2675);
DISPLAY 1.021277 (925 2675);
PAINT ORANGE (925 2675);
DISPLAY INVISIBLE (925 2675);
FORCEPROP 2 LAST SEC 1
J 0
(925 2675);
DISPLAY 0.936170 (925 2675);
PAINT MONO (925 2675);
DISPLAY INVISIBLE (925 2675);
FORCEPROP 2 LAST CDS_LOCATION R6U17
J 0
(920 2575);
DISPLAY 0.617021 (920 2575);
PAINT AQUA (920 2575);
DISPLAY INVISIBLE (920 2575);
FORCEPROP 1 LAST PATH I106
J 0
(925 2625);
DISPLAY 0.978723 (925 2625);
PAINT WHITE (925 2625);
DISPLAY INVISIBLE (925 2625);
FORCEPROP 2 LAST ROOM MEM
J 0
(925 2625);
PAINT MONO (925 2625);
DISPLAY INVISIBLE (925 2625);
FORCEADD RES..2
(1225 1250);
FORCEPROP 1 LAST LOCATION R7M6
J 0
(1270 1375);
DISPLAY 0.617021 (1270 1375);
PAINT AQUA (1270 1375);
FORCEPROP 1 LAST PART_NUMBER G21796-235
J 0
(1265 1125);
DISPLAY 0.617021 (1265 1125);
PAINT BLUE (1265 1125);
FORCEPROP 1 LAST VALUE 665
J 0
(1270 1325);
DISPLAY 0.617021 (1270 1325);
PAINT SKYBLUE (1270 1325);
FORCEPROP 1 LAST TOLERANCE 1.0%
J 0
(1270 1275);
DISPLAY 0.617021 (1270 1275);
PAINT SKYBLUE (1270 1275);
FORCEPROP 1 LAST PACK_TYPE 0402
J 0
(1265 1075);
DISPLAY 0.617021 (1265 1075);
PAINT SKYBLUE (1265 1075);
FORCEPROP 1 LAST MATERIAL CHIP
J 0
(1265 1175);
DISPLAY 0.617021 (1265 1175);
PAINT SKYBLUE (1265 1175);
FORCEPROP 1 LAST WATTAGE 1/16W
J 0
(1265 1225);
DISPLAY 0.617021 (1265 1225);
PAINT SKYBLUE (1265 1225);
FORCEPROP 1 LASTPIN (1225 1150) $PN 2
J 0
(1230 1160);
DISPLAY 0.617021 (1230 1160);
PAINT MONO (1230 1160);
FORCEPROP 1 LASTPIN (1225 1350) $PN 1
J 0
(1230 1312);
DISPLAY 0.617021 (1230 1312);
PAINT MONO (1230 1312);
FORCEPROP 2 LAST CDS_LIB mstr_discrete
J 0
(1225 1250);
PAINT ORANGE (1225 1250);
DISPLAY INVISIBLE (1225 1250);
FORCEPROP 2 LAST BOM_COST SM_CONTROLLER
J 0
(1275 1425);
PAINT MONO (1275 1425);
DISPLAY INVISIBLE (1275 1425);
FORCEPROP 2 LAST SEC_TYPE 0402
J 0
(1275 1475);
DISPLAY 1.021277 (1275 1475);
PAINT ORANGE (1275 1475);
DISPLAY INVISIBLE (1275 1475);
FORCEPROP 2 LAST SEC 1
J 0
(1275 1475);
DISPLAY 0.936170 (1275 1475);
PAINT MONO (1275 1475);
DISPLAY INVISIBLE (1275 1475);
FORCEPROP 2 LAST CDS_LOCATION R7M6
J 0
(1270 1375);
DISPLAY 0.617021 (1270 1375);
PAINT AQUA (1270 1375);
DISPLAY INVISIBLE (1270 1375);
FORCEPROP 1 LAST PATH I107
J 0
(1275 1425);
DISPLAY 0.978723 (1275 1425);
PAINT WHITE (1275 1425);
DISPLAY INVISIBLE (1275 1425);
FORCEPROP 2 LAST ROOM MEM
J 0
(1275 1425);
PAINT MONO (1275 1425);
DISPLAY INVISIBLE (1275 1425);
FORCEADD PVPP_KLM..1
(875 1550);
FORCEPROP 3 LASTPIN (875 1500) SIG_NAME PVPP_KLM\g
J 0
(885 1510);
DISPLAY 0.659574 (885 1510);
PAINT MONO (885 1510);
DISPLAY INVISIBLE (885 1510);
FORCEPROP 1 LAST HDL_POWER PVPP_KLM
J 1
(875 1600);
DISPLAY 0.872340 (875 1600);
PAINT GREEN (875 1600);
DISPLAY INVISIBLE (875 1600);
FORCEPROP 1 LAST BODY_TYPE PLUMBING
J 0
(830 1507);
DISPLAY 0.340426 (830 1507);
PAINT GREEN (830 1507);
DISPLAY INVISIBLE (830 1507);
FORCEPROP 1 LAST VOLTAGE 2.5V
J 0
(830 1507);
DISPLAY 0.340426 (830 1507);
PAINT SKYBLUE (830 1507);
DISPLAY INVISIBLE (830 1507);
FORCEPROP 2 LAST BOM_COST SM_CONTROLLER
J 0
(875 1650);
DISPLAY 1.617021 (875 1650);
PAINT ORANGE (875 1650);
DISPLAY INVISIBLE (875 1650);
FORCEPROP 2 LAST CDS_LIB mstr_symbols
J 0
(875 1550);
PAINT ORANGE (875 1550);
DISPLAY INVISIBLE (875 1550);
FORCEPROP 1 LAST PATH I108
J 0
(925 1575);
DISPLAY 0.872340 (925 1575);
PAINT AQUA (925 1575);
DISPLAY INVISIBLE (925 1575);
FORCEPROP 2 LAST ROOM SMB
J 0
(875 1625);
PAINT MONO (875 1625);
DISPLAY INVISIBLE (875 1625);
FORCEADD RES..2
(875 1250);
FORCEPROP 1 LAST LOCATION R7M1
J 0
(920 1375);
DISPLAY 0.617021 (920 1375);
PAINT AQUA (920 1375);
FORCEPROP 1 LAST PART_NUMBER G21796-235
J 0
(915 1125);
DISPLAY 0.617021 (915 1125);
PAINT BLUE (915 1125);
FORCEPROP 1 LAST VALUE 665
J 0
(920 1325);
DISPLAY 0.617021 (920 1325);
PAINT SKYBLUE (920 1325);
FORCEPROP 1 LAST TOLERANCE 1.0%
J 0
(920 1275);
DISPLAY 0.617021 (920 1275);
PAINT SKYBLUE (920 1275);
FORCEPROP 1 LAST PACK_TYPE 0402
J 0
(915 1075);
DISPLAY 0.617021 (915 1075);
PAINT SKYBLUE (915 1075);
FORCEPROP 1 LAST MATERIAL CHIP
J 0
(915 1175);
DISPLAY 0.617021 (915 1175);
PAINT SKYBLUE (915 1175);
FORCEPROP 1 LAST WATTAGE 1/16W
J 0
(915 1225);
DISPLAY 0.617021 (915 1225);
PAINT SKYBLUE (915 1225);
FORCEPROP 1 LASTPIN (875 1150) $PN 2
J 0
(880 1160);
DISPLAY 0.617021 (880 1160);
PAINT MONO (880 1160);
FORCEPROP 1 LASTPIN (875 1350) $PN 1
J 0
(880 1312);
DISPLAY 0.617021 (880 1312);
PAINT MONO (880 1312);
FORCEPROP 2 LAST BOM_COST SM_CONTROLLER
J 0
(925 1425);
PAINT MONO (925 1425);
DISPLAY INVISIBLE (925 1425);
FORCEPROP 2 LAST CDS_LIB mstr_discrete
J 0
(875 1250);
PAINT ORANGE (875 1250);
DISPLAY INVISIBLE (875 1250);
FORCEPROP 2 LAST SEC_TYPE 0402
J 0
(925 1475);
DISPLAY 1.021277 (925 1475);
PAINT ORANGE (925 1475);
DISPLAY INVISIBLE (925 1475);
FORCEPROP 2 LAST SEC 1
J 0
(925 1475);
DISPLAY 0.936170 (925 1475);
PAINT MONO (925 1475);
DISPLAY INVISIBLE (925 1475);
FORCEPROP 2 LAST CDS_LOCATION R7M1
J 0
(920 1375);
DISPLAY 0.617021 (920 1375);
PAINT AQUA (920 1375);
DISPLAY INVISIBLE (920 1375);
FORCEPROP 1 LAST PATH I109
J 0
(925 1425);
DISPLAY 0.978723 (925 1425);
PAINT WHITE (925 1425);
DISPLAY INVISIBLE (925 1425);
FORCEPROP 2 LAST ROOM MEM
J 0
(925 1425);
PAINT MONO (925 1425);
DISPLAY INVISIBLE (925 1425);
FORCEADD RES..2
(1225 4650);
FORCEPROP 1 LAST LOCATION R4T8
J 0
(1270 4775);
DISPLAY 0.617021 (1270 4775);
PAINT AQUA (1270 4775);
FORCEPROP 1 LAST PART_NUMBER G21796-235
J 0
(1265 4525);
DISPLAY 0.617021 (1265 4525);
PAINT BLUE (1265 4525);
FORCEPROP 1 LAST VALUE 665
J 0
(1270 4725);
DISPLAY 0.617021 (1270 4725);
PAINT SKYBLUE (1270 4725);
FORCEPROP 1 LAST TOLERANCE 1.0%
J 0
(1270 4675);
DISPLAY 0.617021 (1270 4675);
PAINT SKYBLUE (1270 4675);
FORCEPROP 1 LAST PACK_TYPE 0402
J 0
(1265 4475);
DISPLAY 0.617021 (1265 4475);
PAINT SKYBLUE (1265 4475);
FORCEPROP 1 LAST MATERIAL CHIP
J 0
(1265 4575);
DISPLAY 0.617021 (1265 4575);
PAINT SKYBLUE (1265 4575);
FORCEPROP 1 LAST WATTAGE 1/16W
J 0
(1265 4625);
DISPLAY 0.617021 (1265 4625);
PAINT SKYBLUE (1265 4625);
FORCEPROP 1 LASTPIN (1225 4550) $PN 2
J 0
(1230 4560);
DISPLAY 0.617021 (1230 4560);
PAINT MONO (1230 4560);
FORCEPROP 1 LASTPIN (1225 4750) $PN 1
J 0
(1230 4712);
DISPLAY 0.617021 (1230 4712);
PAINT MONO (1230 4712);
FORCEPROP 2 LAST BOM_COST SM_CONTROLLER
J 0
(1275 4825);
PAINT MONO (1275 4825);
DISPLAY INVISIBLE (1275 4825);
FORCEPROP 2 LAST CDS_LIB mstr_discrete
J 0
(1225 4650);
PAINT ORANGE (1225 4650);
DISPLAY INVISIBLE (1225 4650);
FORCEPROP 2 LAST SEC_TYPE 0402
J 0
(1275 4875);
DISPLAY 1.021277 (1275 4875);
PAINT ORANGE (1275 4875);
DISPLAY INVISIBLE (1275 4875);
FORCEPROP 2 LAST SEC 1
J 0
(1275 4875);
DISPLAY 0.936170 (1275 4875);
PAINT MONO (1275 4875);
DISPLAY INVISIBLE (1275 4875);
FORCEPROP 2 LAST CDS_LOCATION R4T8
J 0
(1270 4775);
DISPLAY 0.617021 (1270 4775);
PAINT AQUA (1270 4775);
DISPLAY INVISIBLE (1270 4775);
FORCEPROP 1 LAST PATH I11
J 0
(1275 4825);
DISPLAY 0.978723 (1275 4825);
PAINT WHITE (1275 4825);
DISPLAY INVISIBLE (1275 4825);
FORCEPROP 2 LAST ROOM MEM
J 0
(1275 4825);
PAINT MONO (1275 4825);
DISPLAY INVISIBLE (1275 4825);
FORCEADD RES..1
(-1175 3250);
FORCEPROP 1 LAST LOCATION R3R14
J 0
(-1275 3300);
DISPLAY 0.617021 (-1275 3300);
PAINT AQUA (-1275 3300);
FORCEPROP 1 LAST PART_NUMBER G21796-066
J 0
(-1350 3350);
DISPLAY 0.617021 (-1350 3350);
PAINT BLUE (-1350 3350);
FORCEPROP 1 LAST VALUE 10.0
J 2
(-1000 3250);
DISPLAY 0.617021 (-1000 3250);
PAINT SKYBLUE (-1000 3250);
FORCEPROP 1 LAST TOLERANCE 1%
J 0
(-775 3200);
DISPLAY 0.617021 (-775 3200);
PAINT SKYBLUE (-775 3200);
FORCEPROP 1 LAST PACK_TYPE 0402
J 0
(-1025 3200);
DISPLAY 0.617021 (-1025 3200);
PAINT SKYBLUE (-1025 3200);
FORCEPROP 1 LAST MATERIAL CHIP
J 0
(-1175 3200);
DISPLAY 0.617021 (-1175 3200);
PAINT SKYBLUE (-1175 3200);
FORCEPROP 1 LAST WATTAGE 1/16W
J 2
(-1225 3200);
DISPLAY 0.617021 (-1225 3200);
PAINT SKYBLUE (-1225 3200);
FORCEPROP 1 LASTPIN (-1075 3250) $PN 2
J 0
(-1113 3262);
DISPLAY 0.617021 (-1113 3262);
PAINT MONO (-1113 3262);
FORCEPROP 1 LASTPIN (-1275 3250) $PN 1
J 0
(-1263 3262);
DISPLAY 0.617021 (-1263 3262);
PAINT MONO (-1263 3262);
FORCEPROP 2 LAST CDS_LIB mstr_discrete
J 0
(-1175 3250);
PAINT MONO (-1175 3250);
DISPLAY INVISIBLE (-1175 3250);
FORCEPROP 2 LAST BOM_COST SM_CONTROLLER
J 0
(-1225 3350);
PAINT MONO (-1225 3350);
DISPLAY INVISIBLE (-1225 3350);
FORCEPROP 2 LAST CDS_SEC 1
J 0
(-1225 3450);
DISPLAY 1.404255 (-1225 3450);
PAINT ORANGE (-1225 3450);
DISPLAY INVISIBLE (-1225 3450);
FORCEPROP 2 LAST $SEC 1
J 0
(-1225 3450);
DISPLAY 0.936170 (-1225 3450);
PAINT MONO (-1225 3450);
DISPLAY INVISIBLE (-1225 3450);
FORCEPROP 2 LAST CDS_LOCATION R3R14
J 0
(-1275 3300);
DISPLAY 0.617021 (-1275 3300);
PAINT AQUA (-1275 3300);
DISPLAY INVISIBLE (-1275 3300);
FORCEPROP 1 LAST PATH I110
J 0
(-1225 3400);
DISPLAY 0.978723 (-1225 3400);
PAINT WHITE (-1225 3400);
DISPLAY INVISIBLE (-1225 3400);
FORCEPROP 2 LAST ROOM MEM
J 0
(-1225 3350);
PAINT MONO (-1225 3350);
DISPLAY INVISIBLE (-1225 3350);
FORCEADD RES..1
(-1100 2100);
FORCEPROP 1 LAST LOCATION R6T4
J 0
(-1200 2150);
DISPLAY 0.617021 (-1200 2150);
PAINT AQUA (-1200 2150);
FORCEPROP 1 LAST PART_NUMBER G21796-066
J 0
(-1275 2200);
DISPLAY 0.617021 (-1275 2200);
PAINT BLUE (-1275 2200);
FORCEPROP 1 LAST VALUE 10.0
J 2
(-925 2100);
DISPLAY 0.617021 (-925 2100);
PAINT SKYBLUE (-925 2100);
FORCEPROP 1 LAST TOLERANCE 1%
J 0
(-700 2050);
DISPLAY 0.617021 (-700 2050);
PAINT SKYBLUE (-700 2050);
FORCEPROP 1 LAST PACK_TYPE 0402
J 0
(-950 2050);
DISPLAY 0.617021 (-950 2050);
PAINT SKYBLUE (-950 2050);
FORCEPROP 1 LAST MATERIAL CHIP
J 0
(-1100 2050);
DISPLAY 0.617021 (-1100 2050);
PAINT SKYBLUE (-1100 2050);
FORCEPROP 1 LAST WATTAGE 1/16W
J 2
(-1150 2050);
DISPLAY 0.617021 (-1150 2050);
PAINT SKYBLUE (-1150 2050);
FORCEPROP 1 LASTPIN (-1000 2100) $PN 2
J 0
(-1038 2112);
DISPLAY 0.617021 (-1038 2112);
PAINT MONO (-1038 2112);
FORCEPROP 1 LASTPIN (-1200 2100) $PN 1
J 0
(-1188 2112);
DISPLAY 0.617021 (-1188 2112);
PAINT MONO (-1188 2112);
FORCEPROP 2 LAST CDS_LIB mstr_discrete
J 0
(-1100 2100);
PAINT MONO (-1100 2100);
DISPLAY INVISIBLE (-1100 2100);
FORCEPROP 2 LAST BOM_COST SM_CONTROLLER
J 0
(-1150 2200);
PAINT MONO (-1150 2200);
DISPLAY INVISIBLE (-1150 2200);
FORCEPROP 2 LAST CDS_SEC 1
J 0
(-1150 2300);
DISPLAY 1.404255 (-1150 2300);
PAINT ORANGE (-1150 2300);
DISPLAY INVISIBLE (-1150 2300);
FORCEPROP 2 LAST $SEC 1
J 0
(-1150 2300);
DISPLAY 0.936170 (-1150 2300);
PAINT MONO (-1150 2300);
DISPLAY INVISIBLE (-1150 2300);
FORCEPROP 2 LAST CDS_LOCATION R6T4
J 0
(-1200 2150);
DISPLAY 0.617021 (-1200 2150);
PAINT AQUA (-1200 2150);
DISPLAY INVISIBLE (-1200 2150);
FORCEPROP 1 LAST PATH I111
J 0
(-1150 2250);
DISPLAY 0.978723 (-1150 2250);
PAINT WHITE (-1150 2250);
DISPLAY INVISIBLE (-1150 2250);
FORCEPROP 2 LAST ROOM MEM
J 0
(-1150 2200);
PAINT MONO (-1150 2200);
DISPLAY INVISIBLE (-1150 2200);
FORCEADD RES..1
(-1200 900);
FORCEPROP 1 LAST LOCATION R7M8
J 0
(-1300 950);
DISPLAY 0.617021 (-1300 950);
PAINT AQUA (-1300 950);
FORCEPROP 1 LAST PART_NUMBER G21796-066
J 0
(-1375 1000);
DISPLAY 0.617021 (-1375 1000);
PAINT BLUE (-1375 1000);
FORCEPROP 1 LAST VALUE 10.0
J 2
(-1025 900);
DISPLAY 0.617021 (-1025 900);
PAINT SKYBLUE (-1025 900);
FORCEPROP 1 LAST TOLERANCE 1%
J 0
(-800 850);
DISPLAY 0.617021 (-800 850);
PAINT SKYBLUE (-800 850);
FORCEPROP 1 LAST PACK_TYPE 0402
J 0
(-1050 850);
DISPLAY 0.617021 (-1050 850);
PAINT SKYBLUE (-1050 850);
FORCEPROP 1 LAST MATERIAL CHIP
J 0
(-1200 850);
DISPLAY 0.617021 (-1200 850);
PAINT SKYBLUE (-1200 850);
FORCEPROP 1 LAST WATTAGE 1/16W
J 2
(-1250 850);
DISPLAY 0.617021 (-1250 850);
PAINT SKYBLUE (-1250 850);
FORCEPROP 1 LASTPIN (-1100 900) $PN 2
J 0
(-1138 912);
DISPLAY 0.617021 (-1138 912);
PAINT MONO (-1138 912);
FORCEPROP 1 LASTPIN (-1300 900) $PN 1
J 0
(-1288 912);
DISPLAY 0.617021 (-1288 912);
PAINT MONO (-1288 912);
FORCEPROP 2 LAST BOM_COST SM_CONTROLLER
J 0
(-1250 1000);
PAINT MONO (-1250 1000);
DISPLAY INVISIBLE (-1250 1000);
FORCEPROP 2 LAST CDS_LIB mstr_discrete
J 0
(-1200 900);
PAINT MONO (-1200 900);
DISPLAY INVISIBLE (-1200 900);
FORCEPROP 2 LAST CDS_SEC 1
J 0
(-1250 1100);
DISPLAY 1.404255 (-1250 1100);
PAINT ORANGE (-1250 1100);
DISPLAY INVISIBLE (-1250 1100);
FORCEPROP 2 LAST $SEC 1
J 0
(-1250 1100);
DISPLAY 0.936170 (-1250 1100);
PAINT MONO (-1250 1100);
DISPLAY INVISIBLE (-1250 1100);
FORCEPROP 2 LAST CDS_LOCATION R7M8
J 0
(-1300 950);
DISPLAY 0.617021 (-1300 950);
PAINT AQUA (-1300 950);
DISPLAY INVISIBLE (-1300 950);
FORCEPROP 1 LAST PATH I112
J 0
(-1250 1050);
DISPLAY 0.978723 (-1250 1050);
PAINT WHITE (-1250 1050);
DISPLAY INVISIBLE (-1250 1050);
FORCEPROP 2 LAST ROOM MEM
J 0
(-1250 1000);
PAINT MONO (-1250 1000);
DISPLAY INVISIBLE (-1250 1000);
FORCEADD PVPP_ABC..1
(1475 5100);
FORCEPROP 3 LASTPIN (1475 5050) SIG_NAME PVPP_ABC\g
J 0
(1485 5060);
DISPLAY 0.659574 (1485 5060);
PAINT MONO (1485 5060);
DISPLAY INVISIBLE (1485 5060);
FORCEPROP 1 LAST HDL_POWER PVPP_ABC
J 1
(1475 5150);
DISPLAY 0.872340 (1475 5150);
PAINT GREEN (1475 5150);
DISPLAY INVISIBLE (1475 5150);
FORCEPROP 1 LAST BODY_TYPE PLUMBING
J 0
(1430 5057);
DISPLAY 0.340426 (1430 5057);
PAINT GREEN (1430 5057);
DISPLAY INVISIBLE (1430 5057);
FORCEPROP 1 LAST VOLTAGE 2.5V
J 0
(1430 5057);
DISPLAY 0.340426 (1430 5057);
PAINT SKYBLUE (1430 5057);
DISPLAY INVISIBLE (1430 5057);
FORCEPROP 2 LAST BOM_COST SM_CONTROLLER
J 0
(1475 5200);
DISPLAY 1.617021 (1475 5200);
PAINT ORANGE (1475 5200);
DISPLAY INVISIBLE (1475 5200);
FORCEPROP 2 LAST CDS_LIB mstr_symbols
J 0
(1475 5100);
PAINT ORANGE (1475 5100);
DISPLAY INVISIBLE (1475 5100);
FORCEPROP 1 LAST PATH I113
J 0
(1525 5125);
DISPLAY 0.872340 (1525 5125);
PAINT AQUA (1525 5125);
DISPLAY INVISIBLE (1525 5125);
FORCEPROP 2 LAST ROOM SMB
J 0
(1475 5175);
PAINT MONO (1475 5175);
DISPLAY INVISIBLE (1475 5175);
FORCEADD PVPP_ABC..1
(650 4625);
FORCEPROP 3 LASTPIN (650 4575) SIG_NAME PVPP_ABC\g
J 0
(660 4585);
DISPLAY 0.659574 (660 4585);
PAINT MONO (660 4585);
DISPLAY INVISIBLE (660 4585);
FORCEPROP 1 LAST HDL_POWER PVPP_ABC
J 1
(650 4675);
DISPLAY 0.872340 (650 4675);
PAINT GREEN (650 4675);
DISPLAY INVISIBLE (650 4675);
FORCEPROP 1 LAST BODY_TYPE PLUMBING
J 0
(605 4582);
DISPLAY 0.340426 (605 4582);
PAINT GREEN (605 4582);
DISPLAY INVISIBLE (605 4582);
FORCEPROP 1 LAST VOLTAGE 2.5V
J 0
(605 4582);
DISPLAY 0.340426 (605 4582);
PAINT SKYBLUE (605 4582);
DISPLAY INVISIBLE (605 4582);
FORCEPROP 2 LAST BOM_COST SM_CONTROLLER
J 0
(650 4725);
DISPLAY 1.617021 (650 4725);
PAINT ORANGE (650 4725);
DISPLAY INVISIBLE (650 4725);
FORCEPROP 2 LAST CDS_LIB mstr_symbols
J 0
(650 4625);
PAINT ORANGE (650 4625);
DISPLAY INVISIBLE (650 4625);
FORCEPROP 1 LAST PATH I114
J 0
(700 4650);
DISPLAY 0.872340 (700 4650);
PAINT AQUA (700 4650);
DISPLAY INVISIBLE (700 4650);
FORCEPROP 2 LAST ROOM SMB
J 0
(650 4700);
PAINT MONO (650 4700);
DISPLAY INVISIBLE (650 4700);
FORCEADD PVPP_ABC..1
(875 4950);
FORCEPROP 3 LASTPIN (875 4900) SIG_NAME PVPP_ABC\g
J 0
(885 4910);
DISPLAY 0.659574 (885 4910);
PAINT MONO (885 4910);
DISPLAY INVISIBLE (885 4910);
FORCEPROP 1 LAST HDL_POWER PVPP_ABC
J 1
(875 5000);
DISPLAY 0.872340 (875 5000);
PAINT GREEN (875 5000);
DISPLAY INVISIBLE (875 5000);
FORCEPROP 1 LAST BODY_TYPE PLUMBING
J 0
(830 4907);
DISPLAY 0.340426 (830 4907);
PAINT GREEN (830 4907);
DISPLAY INVISIBLE (830 4907);
FORCEPROP 1 LAST VOLTAGE 2.5V
J 0
(830 4907);
DISPLAY 0.340426 (830 4907);
PAINT SKYBLUE (830 4907);
DISPLAY INVISIBLE (830 4907);
FORCEPROP 2 LAST BOM_COST SM_CONTROLLER
J 0
(875 5050);
DISPLAY 1.617021 (875 5050);
PAINT ORANGE (875 5050);
DISPLAY INVISIBLE (875 5050);
FORCEPROP 2 LAST CDS_LIB mstr_symbols
J 0
(875 4950);
PAINT ORANGE (875 4950);
DISPLAY INVISIBLE (875 4950);
FORCEPROP 1 LAST PATH I12
J 0
(925 4975);
DISPLAY 0.872340 (925 4975);
PAINT AQUA (925 4975);
DISPLAY INVISIBLE (925 4975);
FORCEPROP 2 LAST ROOM SMB
J 0
(875 5025);
PAINT MONO (875 5025);
DISPLAY INVISIBLE (875 5025);
FORCEADD RES..2
(875 4650);
FORCEPROP 1 LAST LOCATION R4T7
J 0
(920 4775);
DISPLAY 0.617021 (920 4775);
PAINT AQUA (920 4775);
FORCEPROP 1 LAST PART_NUMBER G21796-235
J 0
(915 4525);
DISPLAY 0.617021 (915 4525);
PAINT BLUE (915 4525);
FORCEPROP 1 LAST VALUE 665
J 0
(920 4725);
DISPLAY 0.617021 (920 4725);
PAINT SKYBLUE (920 4725);
FORCEPROP 1 LAST TOLERANCE 1.0%
J 0
(920 4675);
DISPLAY 0.617021 (920 4675);
PAINT SKYBLUE (920 4675);
FORCEPROP 1 LAST PACK_TYPE 0402
J 0
(915 4475);
DISPLAY 0.617021 (915 4475);
PAINT SKYBLUE (915 4475);
FORCEPROP 1 LAST MATERIAL CHIP
J 0
(915 4575);
DISPLAY 0.617021 (915 4575);
PAINT SKYBLUE (915 4575);
FORCEPROP 1 LAST WATTAGE 1/16W
J 0
(915 4625);
DISPLAY 0.617021 (915 4625);
PAINT SKYBLUE (915 4625);
FORCEPROP 1 LASTPIN (875 4550) $PN 2
J 0
(880 4560);
DISPLAY 0.617021 (880 4560);
PAINT MONO (880 4560);
FORCEPROP 1 LASTPIN (875 4750) $PN 1
J 0
(880 4712);
DISPLAY 0.617021 (880 4712);
PAINT MONO (880 4712);
FORCEPROP 2 LAST CDS_LIB mstr_discrete
J 0
(875 4650);
PAINT ORANGE (875 4650);
DISPLAY INVISIBLE (875 4650);
FORCEPROP 2 LAST BOM_COST SM_CONTROLLER
J 0
(925 4825);
PAINT MONO (925 4825);
DISPLAY INVISIBLE (925 4825);
FORCEPROP 2 LAST SEC_TYPE 0402
J 0
(925 4875);
DISPLAY 1.021277 (925 4875);
PAINT ORANGE (925 4875);
DISPLAY INVISIBLE (925 4875);
FORCEPROP 2 LAST SEC 1
J 0
(925 4875);
DISPLAY 0.936170 (925 4875);
PAINT MONO (925 4875);
DISPLAY INVISIBLE (925 4875);
FORCEPROP 2 LAST CDS_LOCATION R4T7
J 0
(920 4775);
DISPLAY 0.617021 (920 4775);
PAINT AQUA (920 4775);
DISPLAY INVISIBLE (920 4775);
FORCEPROP 1 LAST PATH I13
J 0
(925 4825);
DISPLAY 0.978723 (925 4825);
PAINT WHITE (925 4825);
DISPLAY INVISIBLE (925 4825);
FORCEPROP 2 LAST ROOM MEM
J 0
(925 4825);
PAINT MONO (925 4825);
DISPLAY INVISIBLE (925 4825);
FORCEADD PCA9617..1
(150 4300);
FORCEPROP 1 LAST POWER_GROUP GND=GND
J 0
(-200 4050);
DISPLAY 0.617021 (-200 4050);
PAINT ORANGE (-200 4050);
FORCEPROP 1 LAST LOCATION U6F1
J 0
(-200 4625);
DISPLAY 0.617021 (-200 4625);
PAINT AQUA (-200 4625);
FORCEPROP 1 LAST PART_NUMBER G81764-001
J 0
(-200 4100);
DISPLAY 0.617021 (-200 4100);
PAINT BLUE (-200 4100);
FORCEPROP 1 LAST MATERIAL IC
J 0
(-200 4575);
DISPLAY 0.617021 (-200 4575);
PAINT SKYBLUE (-200 4575);
FORCEPROP 2 LASTPIN (550 4450) $PN 8
J 0
(560 4460);
DISPLAY 0.617021 (560 4460);
PAINT MONO (560 4460);
FORCEPROP 2 LASTPIN (-250 4450) $PN 1
J 2
(-260 4460);
DISPLAY 0.617021 (-260 4460);
PAINT MONO (-260 4460);
FORCEPROP 2 LASTPIN (550 4300) $PN 6
J 0
(560 4310);
DISPLAY 0.617021 (560 4310);
PAINT MONO (560 4310);
FORCEPROP 2 LASTPIN (-250 4300) $PN 3
J 2
(-260 4310);
DISPLAY 0.617021 (-260 4310);
PAINT MONO (-260 4310);
FORCEPROP 2 LASTPIN (550 4350) $PN 7
J 0
(560 4360);
DISPLAY 0.617021 (560 4360);
PAINT MONO (560 4360);
FORCEPROP 2 LASTPIN (-250 4350) $PN 2
J 2
(-260 4360);
DISPLAY 0.617021 (-260 4360);
PAINT MONO (-260 4360);
FORCEPROP 2 LASTPIN (-250 4200) $PN 5
J 2
(-260 4210);
DISPLAY 0.617021 (-260 4210);
PAINT MONO (-260 4210);
FORCEPROP 1 LAST PACK_TYPE SSOP
J 0
(-200 4675);
PAINT SKYBLUE (-200 4675);
DISPLAY INVISIBLE (-200 4675);
FORCEPROP 2 LAST CDS_LIB mstr_digital
J 0
(150 4300);
PAINT MONO (150 4300);
DISPLAY INVISIBLE (150 4300);
FORCEPROP 2 LAST BOM_COST SM_CONTROLLER
J 0
(-200 4675);
PAINT MONO (-200 4675);
DISPLAY INVISIBLE (-200 4675);
FORCEPROP 2 LAST CDS_SEC 1
J 0
(-200 4675);
DISPLAY 1.404255 (-200 4675);
PAINT ORANGE (-200 4675);
DISPLAY INVISIBLE (-200 4675);
FORCEPROP 2 LAST $SEC 1
J 0
(-200 4675);
DISPLAY 0.936170 (-200 4675);
PAINT MONO (-200 4675);
DISPLAY INVISIBLE (-200 4675);
FORCEPROP 2 LAST CDS_LOCATION U6F1
J 0
(-200 4625);
DISPLAY 0.617021 (-200 4625);
PAINT AQUA (-200 4625);
DISPLAY INVISIBLE (-200 4625);
FORCEPROP 1 LAST PATH I15
J 0
(275 4575);
PAINT GREEN (275 4575);
DISPLAY INVISIBLE (275 4575);
FORCEPROP 2 LAST ROOM MEM
J 0
(-200 4675);
PAINT MONO (-200 4675);
DISPLAY INVISIBLE (-200 4675);
FORCEADD PVCCIO_CPU0..1
(-475 4875);
FORCEPROP 3 LASTPIN (-475 4825) SIG_NAME PVCCIO_CPU0\g
J 0
(-465 4835);
DISPLAY 0.659574 (-465 4835);
PAINT MONO (-465 4835);
DISPLAY INVISIBLE (-465 4835);
FORCEPROP 1 LAST HDL_POWER PVCCIO_CPU0
J 1
(-475 4925);
DISPLAY 0.872340 (-475 4925);
PAINT GREEN (-475 4925);
DISPLAY INVISIBLE (-475 4925);
FORCEPROP 1 LAST BODY_TYPE PLUMBING
J 0
(-520 4832);
DISPLAY 0.340426 (-520 4832);
PAINT GREEN (-520 4832);
DISPLAY INVISIBLE (-520 4832);
FORCEPROP 1 LAST VOLTAGE 1.1V
J 0
(-520 4832);
DISPLAY 0.340426 (-520 4832);
PAINT SKYBLUE (-520 4832);
DISPLAY INVISIBLE (-520 4832);
FORCEPROP 2 LAST CDS_LIB mstr_symbols
J 0
(-475 4875);
PAINT ORANGE (-475 4875);
DISPLAY INVISIBLE (-475 4875);
FORCEPROP 1 LAST PATH I16
J 0
(-425 4900);
DISPLAY 0.872340 (-425 4900);
PAINT AQUA (-425 4900);
DISPLAY INVISIBLE (-425 4900);
FORCEADD RES..2
R 2
(-650 4650);
FORCEPROP 1 LAST LOCATION R4T6
J 2
(-695 4775);
DISPLAY 0.617021 (-695 4775);
PAINT AQUA (-695 4775);
FORCEPROP 1 LAST PART_NUMBER G21796-294
J 2
(-690 4525);
DISPLAY 0.617021 (-690 4525);
PAINT BLUE (-690 4525);
FORCEPROP 1 LAST VALUE 240
J 2
(-695 4725);
DISPLAY 0.617021 (-695 4725);
PAINT SKYBLUE (-695 4725);
FORCEPROP 1 LAST TOLERANCE 1.0%
J 2
(-695 4675);
DISPLAY 0.617021 (-695 4675);
PAINT SKYBLUE (-695 4675);
FORCEPROP 1 LAST PACK_TYPE 0402
J 2
(-690 4475);
DISPLAY 0.617021 (-690 4475);
PAINT SKYBLUE (-690 4475);
FORCEPROP 1 LAST MATERIAL CHIP
J 2
(-690 4575);
DISPLAY 0.617021 (-690 4575);
PAINT SKYBLUE (-690 4575);
FORCEPROP 1 LAST WATTAGE 1/16W
J 2
(-690 4625);
DISPLAY 0.617021 (-690 4625);
PAINT SKYBLUE (-690 4625);
FORCEPROP 1 LASTPIN (-650 4550) $PN 2
J 2
(-655 4560);
DISPLAY 0.617021 (-655 4560);
PAINT MONO (-655 4560);
FORCEPROP 1 LASTPIN (-650 4750) $PN 1
J 2
(-655 4712);
DISPLAY 0.617021 (-655 4712);
PAINT MONO (-655 4712);
FORCEPROP 2 LAST CDS_LIB mstr_discrete
J 0
(-650 4650);
PAINT MONO (-650 4650);
DISPLAY INVISIBLE (-650 4650);
FORCEPROP 2 LAST SIGNAL_MODEL DEFAULT_RESISTOR_750OHM_2_1
J 0
(-700 4900);
DISPLAY 1.617021 (-700 4900);
PAINT MONO (-700 4900);
DISPLAY INVISIBLE (-700 4900);
FORCEPROP 2 LAST CD_SEC 1
J 0
(-700 4900);
DISPLAY 1.617021 (-700 4900);
PAINT MONO (-700 4900);
DISPLAY INVISIBLE (-700 4900);
FORCEPROP 2 LAST BOM_COST SM_CONTROLLER
J 2
(-1225 4750);
DISPLAY 1.617021 (-1225 4750);
PAINT PEACH (-1225 4750);
DISPLAY INVISIBLE (-1225 4750);
FORCEPROP 2 LAST CDS_SEC 1
J 0
(-700 4875);
DISPLAY 1.404255 (-700 4875);
PAINT ORANGE (-700 4875);
DISPLAY INVISIBLE (-700 4875);
FORCEPROP 2 LAST $SEC 1
J 0
(-700 4875);
DISPLAY 0.936170 (-700 4875);
PAINT MONO (-700 4875);
DISPLAY INVISIBLE (-700 4875);
FORCEPROP 2 LAST CDS_LOCATION R4T6
J 2
(-695 4775);
DISPLAY 0.617021 (-695 4775);
PAINT AQUA (-695 4775);
DISPLAY INVISIBLE (-695 4775);
FORCEPROP 1 LAST PATH I17
J 2
(-700 4825);
DISPLAY 0.978723 (-700 4825);
PAINT WHITE (-700 4825);
DISPLAY INVISIBLE (-700 4825);
FORCEPROP 2 LAST ROOM MEM
J 0
(-675 4800);
PAINT MONO (-675 4800);
DISPLAY INVISIBLE (-675 4800);
FORCEADD PVCCIO_CPU0..1
(-900 4975);
FORCEPROP 3 LASTPIN (-900 4925) SIG_NAME PVCCIO_CPU0\g
J 0
(-890 4935);
DISPLAY 0.659574 (-890 4935);
PAINT MONO (-890 4935);
DISPLAY INVISIBLE (-890 4935);
FORCEPROP 1 LAST HDL_POWER PVCCIO_CPU0
J 1
(-900 5025);
DISPLAY 0.872340 (-900 5025);
PAINT GREEN (-900 5025);
DISPLAY INVISIBLE (-900 5025);
FORCEPROP 1 LAST BODY_TYPE PLUMBING
J 0
(-945 4932);
DISPLAY 0.340426 (-945 4932);
PAINT GREEN (-945 4932);
DISPLAY INVISIBLE (-945 4932);
FORCEPROP 1 LAST VOLTAGE 1.1V
J 0
(-945 4932);
DISPLAY 0.340426 (-945 4932);
PAINT SKYBLUE (-945 4932);
DISPLAY INVISIBLE (-945 4932);
FORCEPROP 2 LAST CDS_LIB mstr_symbols
J 0
(-900 4975);
PAINT ORANGE (-900 4975);
DISPLAY INVISIBLE (-900 4975);
FORCEPROP 1 LAST PATH I18
J 0
(-850 5000);
DISPLAY 0.872340 (-850 5000);
PAINT AQUA (-850 5000);
DISPLAY INVISIBLE (-850 5000);
FORCEADD RES..2
R 2
(-1025 4650);
FORCEPROP 1 LAST LOCATION R4T5
J 2
(-1070 4775);
DISPLAY 0.617021 (-1070 4775);
PAINT AQUA (-1070 4775);
FORCEPROP 1 LAST PART_NUMBER G21796-294
J 2
(-1065 4525);
DISPLAY 0.617021 (-1065 4525);
PAINT BLUE (-1065 4525);
FORCEPROP 1 LAST VALUE 240
J 2
(-1070 4725);
DISPLAY 0.617021 (-1070 4725);
PAINT SKYBLUE (-1070 4725);
FORCEPROP 1 LAST TOLERANCE 1.0%
J 2
(-1070 4675);
DISPLAY 0.617021 (-1070 4675);
PAINT SKYBLUE (-1070 4675);
FORCEPROP 1 LAST PACK_TYPE 0402
J 2
(-1065 4475);
DISPLAY 0.617021 (-1065 4475);
PAINT SKYBLUE (-1065 4475);
FORCEPROP 1 LAST MATERIAL CHIP
J 2
(-1065 4575);
DISPLAY 0.617021 (-1065 4575);
PAINT SKYBLUE (-1065 4575);
FORCEPROP 1 LAST WATTAGE 1/16W
J 2
(-1065 4625);
DISPLAY 0.617021 (-1065 4625);
PAINT SKYBLUE (-1065 4625);
FORCEPROP 1 LASTPIN (-1025 4550) $PN 2
J 2
(-1030 4560);
DISPLAY 0.617021 (-1030 4560);
PAINT MONO (-1030 4560);
FORCEPROP 1 LASTPIN (-1025 4750) $PN 1
J 2
(-1030 4712);
DISPLAY 0.617021 (-1030 4712);
PAINT MONO (-1030 4712);
FORCEPROP 2 LAST CD_SEC 1
J 0
(-1075 4900);
DISPLAY 1.617021 (-1075 4900);
PAINT MONO (-1075 4900);
DISPLAY INVISIBLE (-1075 4900);
FORCEPROP 2 LAST SIGNAL_MODEL DEFAULT_RESISTOR_750OHM_2_1
J 0
(-1075 4900);
DISPLAY 1.617021 (-1075 4900);
PAINT MONO (-1075 4900);
DISPLAY INVISIBLE (-1075 4900);
FORCEPROP 2 LAST CDS_LIB mstr_discrete
J 0
(-1025 4650);
PAINT MONO (-1025 4650);
DISPLAY INVISIBLE (-1025 4650);
FORCEPROP 2 LAST BOM_COST SM_CONTROLLER
J 2
(-1600 4750);
DISPLAY 1.617021 (-1600 4750);
PAINT PEACH (-1600 4750);
DISPLAY INVISIBLE (-1600 4750);
FORCEPROP 2 LAST CDS_SEC 1
J 0
(-1075 4875);
DISPLAY 1.404255 (-1075 4875);
PAINT ORANGE (-1075 4875);
DISPLAY INVISIBLE (-1075 4875);
FORCEPROP 2 LAST $SEC 1
J 0
(-1075 4875);
DISPLAY 0.936170 (-1075 4875);
PAINT MONO (-1075 4875);
DISPLAY INVISIBLE (-1075 4875);
FORCEPROP 2 LAST CDS_LOCATION R4T5
J 2
(-1070 4775);
DISPLAY 0.617021 (-1070 4775);
PAINT AQUA (-1070 4775);
DISPLAY INVISIBLE (-1070 4775);
FORCEPROP 1 LAST PATH I19
J 2
(-1075 4825);
DISPLAY 0.978723 (-1075 4825);
PAINT WHITE (-1075 4825);
DISPLAY INVISIBLE (-1075 4825);
FORCEPROP 2 LAST ROOM MEM
J 0
(-1050 4800);
PAINT MONO (-1050 4800);
DISPLAY INVISIBLE (-1050 4800);
FORCEADD CAP_A..1
(1900 4925);
FORCEPROP 1 LAST LOCATION C6F2
J 0
(1950 5025);
DISPLAY 0.617021 (1950 5025);
PAINT AQUA (1950 5025);
FORCEPROP 1 LAST PART_NUMBER A36096-030
J 0
(1950 4775);
DISPLAY 0.617021 (1950 4775);
PAINT BLUE (1950 4775);
FORCEPROP 1 LAST VALUE 0.1UF
J 0
(1950 4975);
DISPLAY 0.617021 (1950 4975);
PAINT SKYBLUE (1950 4975);
FORCEPROP 1 LAST TOLERANCE 10%
J 0
(1950 4875);
DISPLAY 0.617021 (1950 4875);
PAINT SKYBLUE (1950 4875);
FORCEPROP 1 LAST PACK_TYPE 0402V
J 0
(1950 4725);
DISPLAY 0.617021 (1950 4725);
PAINT SKYBLUE (1950 4725);
FORCEPROP 1 LAST VOLTAGE 16V
J 0
(1950 4925);
DISPLAY 0.617021 (1950 4925);
PAINT SKYBLUE (1950 4925);
FORCEPROP 1 LAST MATERIAL X7R
J 0
(1950 4825);
DISPLAY 0.617021 (1950 4825);
PAINT SKYBLUE (1950 4825);
FORCEPROP 1 LASTPIN (1900 5025) $PN 1
J 0
(1910 5005);
DISPLAY 0.617021 (1910 5005);
PAINT MONO (1910 5005);
FORCEPROP 1 LASTPIN (1900 4825) $PN 2
J 0
(1910 4805);
DISPLAY 0.617021 (1910 4805);
PAINT MONO (1910 4805);
FORCEPROP 1 LAST PATH I2
J 0
(1950 5075);
DISPLAY 0.978723 (1950 5075);
PAINT WHITE (1950 5075);
DISPLAY INVISIBLE (1950 5075);
FORCEPROP 2 LAST ROOM MEM
J 0
(1950 5050);
PAINT MONO (1950 5050);
DISPLAY INVISIBLE (1950 5050);
FORCEPROP 2 LAST CDS_LOCATION C6F2
J 0
(1950 5025);
DISPLAY 0.617021 (1950 5025);
PAINT AQUA (1950 5025);
DISPLAY INVISIBLE (1950 5025);
FORCEPROP 2 LAST BOM_COST SM_CONTROLLER
J 0
(1950 5075);
DISPLAY 2.170213 (1950 5075);
PAINT ORANGE (1950 5075);
DISPLAY INVISIBLE (1950 5075);
FORCEPROP 2 LAST CD_SEC 1
J 0
(1950 5150);
DISPLAY 1.617021 (1950 5150);
PAINT MONO (1950 5150);
DISPLAY INVISIBLE (1950 5150);
FORCEPROP 2 LAST SIGNAL_MODEL DEFAULT_CAPACITOR_100000pF_2_1
J 0
(1950 5150);
DISPLAY 1.617021 (1950 5150);
PAINT MONO (1950 5150);
DISPLAY INVISIBLE (1950 5150);
FORCEPROP 2 LAST CDS_LIB dev_discrete
J 0
(1900 4925);
PAINT ORANGE (1900 4925);
DISPLAY INVISIBLE (1900 4925);
FORCEPROP 2 LAST CDS_SEC 1
J 0
(1950 5125);
DISPLAY 1.404255 (1950 5125);
PAINT ORANGE (1950 5125);
DISPLAY INVISIBLE (1950 5125);
FORCEPROP 2 LAST $SEC 1
J 0
(1950 5125);
DISPLAY 0.936170 (1950 5125);
PAINT MONO (1950 5125);
DISPLAY INVISIBLE (1950 5125);
FORCEADD RES..1
(-1075 4300);
FORCEPROP 1 LAST LOCATION R4T4
J 0
(-1175 4350);
DISPLAY 0.617021 (-1175 4350);
PAINT AQUA (-1175 4350);
FORCEPROP 1 LAST PART_NUMBER G21796-066
J 0
(-1250 4400);
DISPLAY 0.617021 (-1250 4400);
PAINT BLUE (-1250 4400);
FORCEPROP 1 LAST VALUE 10.0
J 2
(-900 4300);
DISPLAY 0.617021 (-900 4300);
PAINT SKYBLUE (-900 4300);
FORCEPROP 1 LAST TOLERANCE 1%
J 0
(-675 4250);
DISPLAY 0.617021 (-675 4250);
PAINT SKYBLUE (-675 4250);
FORCEPROP 1 LAST PACK_TYPE 0402
J 0
(-925 4250);
DISPLAY 0.617021 (-925 4250);
PAINT SKYBLUE (-925 4250);
FORCEPROP 1 LAST MATERIAL CHIP
J 0
(-1075 4250);
DISPLAY 0.617021 (-1075 4250);
PAINT SKYBLUE (-1075 4250);
FORCEPROP 1 LAST WATTAGE 1/16W
J 2
(-1125 4250);
DISPLAY 0.617021 (-1125 4250);
PAINT SKYBLUE (-1125 4250);
FORCEPROP 1 LASTPIN (-975 4300) $PN 2
J 0
(-1013 4312);
DISPLAY 0.617021 (-1013 4312);
PAINT MONO (-1013 4312);
FORCEPROP 1 LASTPIN (-1175 4300) $PN 1
J 0
(-1163 4312);
DISPLAY 0.617021 (-1163 4312);
PAINT MONO (-1163 4312);
FORCEPROP 2 LAST CDS_LIB mstr_discrete
J 0
(-1075 4300);
PAINT MONO (-1075 4300);
DISPLAY INVISIBLE (-1075 4300);
FORCEPROP 2 LAST BOM_COST SM_CONTROLLER
J 0
(-1125 4400);
PAINT MONO (-1125 4400);
DISPLAY INVISIBLE (-1125 4400);
FORCEPROP 2 LAST CDS_SEC 1
J 0
(-1125 4500);
DISPLAY 1.404255 (-1125 4500);
PAINT ORANGE (-1125 4500);
DISPLAY INVISIBLE (-1125 4500);
FORCEPROP 2 LAST $SEC 1
J 0
(-1125 4500);
DISPLAY 0.936170 (-1125 4500);
PAINT MONO (-1125 4500);
DISPLAY INVISIBLE (-1125 4500);
FORCEPROP 2 LAST CDS_LOCATION R4T4
J 0
(-1175 4350);
DISPLAY 0.617021 (-1175 4350);
PAINT AQUA (-1175 4350);
DISPLAY INVISIBLE (-1175 4350);
FORCEPROP 1 LAST PATH I20
J 0
(-1125 4450);
DISPLAY 0.978723 (-1125 4450);
PAINT WHITE (-1125 4450);
DISPLAY INVISIBLE (-1125 4450);
FORCEPROP 2 LAST ROOM MEM
J 0
(-1125 4400);
PAINT MONO (-1125 4400);
DISPLAY INVISIBLE (-1125 4400);
FORCEADD PVCCIO_CPU0..1
(2125 3950);
FORCEPROP 3 LASTPIN (2125 3900) SIG_NAME PVCCIO_CPU0\g
J 0
(2135 3910);
DISPLAY 0.659574 (2135 3910);
PAINT MONO (2135 3910);
DISPLAY INVISIBLE (2135 3910);
FORCEPROP 1 LAST HDL_POWER PVCCIO_CPU0
J 1
(2125 4000);
DISPLAY 0.872340 (2125 4000);
PAINT GREEN (2125 4000);
DISPLAY INVISIBLE (2125 4000);
FORCEPROP 1 LAST BODY_TYPE PLUMBING
J 0
(2080 3907);
DISPLAY 0.340426 (2080 3907);
PAINT GREEN (2080 3907);
DISPLAY INVISIBLE (2080 3907);
FORCEPROP 1 LAST VOLTAGE 1.1V
J 0
(2080 3907);
DISPLAY 0.340426 (2080 3907);
PAINT SKYBLUE (2080 3907);
DISPLAY INVISIBLE (2080 3907);
FORCEPROP 2 LAST CDS_LIB mstr_symbols
J 0
(2125 3950);
PAINT ORANGE (2125 3950);
DISPLAY INVISIBLE (2125 3950);
FORCEPROP 1 LAST PATH I21
J 0
(2175 3975);
DISPLAY 0.872340 (2175 3975);
PAINT AQUA (2175 3975);
DISPLAY INVISIBLE (2175 3975);
FORCEADD GND..1
(2125 3525);
FORCEPROP 3 LASTPIN (2125 3575) SIG_NAME GND\g
J 0
(2135 3585);
DISPLAY 0.659574 (2135 3585);
PAINT MONO (2135 3585);
DISPLAY INVISIBLE (2135 3585);
FORCEPROP 1 LAST HDL_POWER GND
J 0
(2125 3675);
DISPLAY 2.361702 (2125 3675);
PAINT GREEN (2125 3675);
DISPLAY INVISIBLE (2125 3675);
FORCEPROP 1 LAST BODY_TYPE PLUMBING
J 0
(2080 3482);
DISPLAY 0.340426 (2080 3482);
PAINT GREEN (2080 3482);
DISPLAY INVISIBLE (2080 3482);
FORCEPROP 1 LAST VOLTAGE 0
J 0
(2125 3525);
PAINT SKYBLUE (2125 3525);
DISPLAY INVISIBLE (2125 3525);
FORCEPROP 2 LAST BOM_COST SM_CONTROLLER
J 0
(1725 3600);
DISPLAY 1.617021 (1725 3600);
PAINT ORANGE (1725 3600);
DISPLAY INVISIBLE (1725 3600);
FORCEPROP 2 LAST CDS_LIB mstr_symbols
J 0
(2125 3525);
PAINT MONO (2125 3525);
DISPLAY INVISIBLE (2125 3525);
FORCEPROP 1 LAST SIZE 1B
J 0
(2200 3475);
DISPLAY 2.361702 (2200 3475);
PAINT GREEN (2200 3475);
DISPLAY INVISIBLE (2200 3475);
FORCEPROP 1 LAST PATH I22
J 0
(2200 3525);
DISPLAY 0.872340 (2200 3525);
PAINT AQUA (2200 3525);
DISPLAY INVISIBLE (2200 3525);
FORCEPROP 2 LAST ROOM SMB
J 0
(2025 3600);
PAINT MONO (2025 3600);
DISPLAY INVISIBLE (2025 3600);
FORCEADD CAP_A..1
(2125 3775);
FORCEPROP 1 LAST LOCATION C7E1
J 0
(2175 3875);
DISPLAY 0.617021 (2175 3875);
PAINT AQUA (2175 3875);
FORCEPROP 1 LAST PART_NUMBER A36096-030
J 0
(2175 3625);
DISPLAY 0.617021 (2175 3625);
PAINT BLUE (2175 3625);
FORCEPROP 1 LAST VALUE 0.1UF
J 0
(2175 3825);
DISPLAY 0.617021 (2175 3825);
PAINT SKYBLUE (2175 3825);
FORCEPROP 1 LAST TOLERANCE 10%
J 0
(2175 3725);
DISPLAY 0.617021 (2175 3725);
PAINT SKYBLUE (2175 3725);
FORCEPROP 1 LAST PACK_TYPE 0402V
J 0
(2175 3575);
DISPLAY 0.617021 (2175 3575);
PAINT SKYBLUE (2175 3575);
FORCEPROP 1 LAST VOLTAGE 16V
J 0
(2175 3775);
DISPLAY 0.617021 (2175 3775);
PAINT SKYBLUE (2175 3775);
FORCEPROP 1 LAST MATERIAL X7R
J 0
(2175 3675);
DISPLAY 0.617021 (2175 3675);
PAINT SKYBLUE (2175 3675);
FORCEPROP 1 LASTPIN (2125 3875) $PN 1
J 0
(2135 3855);
DISPLAY 0.617021 (2135 3855);
PAINT MONO (2135 3855);
FORCEPROP 1 LASTPIN (2125 3675) $PN 2
J 0
(2135 3655);
DISPLAY 0.617021 (2135 3655);
PAINT MONO (2135 3655);
FORCEPROP 1 LAST PATH I23
J 0
(2175 3925);
DISPLAY 0.978723 (2175 3925);
PAINT WHITE (2175 3925);
DISPLAY INVISIBLE (2175 3925);
FORCEPROP 2 LAST ROOM MEM
J 0
(2175 3900);
PAINT MONO (2175 3900);
DISPLAY INVISIBLE (2175 3900);
FORCEPROP 2 LAST CDS_LOCATION C7E1
J 0
(2175 3875);
DISPLAY 0.617021 (2175 3875);
PAINT AQUA (2175 3875);
DISPLAY INVISIBLE (2175 3875);
FORCEPROP 2 LAST SIGNAL_MODEL DEFAULT_CAPACITOR_100000pF_2_1
J 0
(2175 4000);
DISPLAY 1.617021 (2175 4000);
PAINT MONO (2175 4000);
DISPLAY INVISIBLE (2175 4000);
FORCEPROP 2 LAST CD_SEC 1
J 0
(2175 4000);
DISPLAY 1.617021 (2175 4000);
PAINT MONO (2175 4000);
DISPLAY INVISIBLE (2175 4000);
FORCEPROP 2 LAST BOM_COST SM_CONTROLLER
J 0
(2175 3925);
DISPLAY 2.170213 (2175 3925);
PAINT ORANGE (2175 3925);
DISPLAY INVISIBLE (2175 3925);
FORCEPROP 2 LAST CDS_LIB dev_discrete
J 0
(2125 3775);
PAINT ORANGE (2125 3775);
DISPLAY INVISIBLE (2125 3775);
FORCEPROP 2 LAST CDS_SEC 1
J 0
(2175 3975);
DISPLAY 1.404255 (2175 3975);
PAINT ORANGE (2175 3975);
DISPLAY INVISIBLE (2175 3975);
FORCEPROP 2 LAST $SEC 1
J 0
(2175 3975);
DISPLAY 0.936170 (2175 3975);
PAINT MONO (2175 3975);
DISPLAY INVISIBLE (2175 3975);
FORCEADD OFFPAGE..2
(2600 3300);
FORCEPROP 2 LAST $XR0 49 
J 0
(2789 3300);
DISPLAY 0.638298 (2789 3300);
PAINT MONO (2789 3300);
FORCEPROP 2 LAST $XR1 50 
J 0
(2879 3300);
DISPLAY 0.638298 (2879 3300);
PAINT MONO (2879 3300);
FORCEPROP 2 LAST $XR2 51 
J 0
(2969 3300);
DISPLAY 0.638298 (2969 3300);
PAINT MONO (2969 3300);
FORCEPROP 2 LAST $XR3 52 
J 0
(3059 3300);
DISPLAY 0.638298 (3059 3300);
PAINT MONO (3059 3300);
FORCEPROP 2 LAST $XR4 53 
J 0
(3149 3300);
DISPLAY 0.638298 (3149 3300);
PAINT MONO (3149 3300);
FORCEPROP 2 LAST $XR5 54 
J 0
(3239 3300);
DISPLAY 0.638298 (3239 3300);
PAINT MONO (3239 3300);
FORCEPROP 1 LAST COMMENT_BODY TRUE
J 0
(2555 3205);
DISPLAY 0.872340 (2555 3205);
PAINT GREEN (2555 3205);
DISPLAY INVISIBLE (2555 3205);
FORCEPROP 1 LAST OFFPAGE TRUE
J 0
(2925 3175);
PAINT GREEN (2925 3175);
DISPLAY INVISIBLE (2925 3175);
FORCEPROP 2 LAST CDS_LIB mstr_standard
J 0
(2600 3300);
PAINT ORANGE (2600 3300);
DISPLAY INVISIBLE (2600 3300);
FORCEPROP 2 LAST BOM_COST SM_CONTROLLER
J 0
(2925 3350);
PAINT MONO (2925 3350);
DISPLAY INVISIBLE (2925 3350);
FORCEPROP 2 LAST PATH I24
J 0
(2900 3350);
DISPLAY 1.021277 (2900 3350);
PAINT ORANGE (2900 3350);
DISPLAY INVISIBLE (2900 3350);
FORCEADD OFFPAGE..3
(2600 3250);
FORCEPROP 2 LAST $XR0 49 
J 0
(2814 3250);
DISPLAY 0.638298 (2814 3250);
PAINT MONO (2814 3250);
FORCEPROP 2 LAST $XR1 50 
J 0
(2904 3250);
DISPLAY 0.638298 (2904 3250);
PAINT MONO (2904 3250);
FORCEPROP 2 LAST $XR2 51 
J 0
(2994 3250);
DISPLAY 0.638298 (2994 3250);
PAINT MONO (2994 3250);
FORCEPROP 2 LAST $XR3 52 
J 0
(3084 3250);
DISPLAY 0.638298 (3084 3250);
PAINT MONO (3084 3250);
FORCEPROP 2 LAST $XR4 53 
J 0
(3174 3250);
DISPLAY 0.638298 (3174 3250);
PAINT MONO (3174 3250);
FORCEPROP 2 LAST $XR5 54 
J 0
(3264 3250);
DISPLAY 0.638298 (3264 3250);
PAINT MONO (3264 3250);
FORCEPROP 1 LAST COMMENT_BODY TRUE
J 0
(2550 3150);
DISPLAY 1.872340 (2550 3150);
PAINT GREEN (2550 3150);
DISPLAY INVISIBLE (2550 3150);
FORCEPROP 1 LAST OFFPAGE TRUE
J 0
(2925 3125);
PAINT GREEN (2925 3125);
DISPLAY INVISIBLE (2925 3125);
FORCEPROP 2 LAST ROOM SMB
J 0
(3375 3300);
PAINT MONO (3375 3300);
DISPLAY INVISIBLE (3375 3300);
FORCEPROP 2 LAST CDS_LIB mstr_standard
J 0
(2600 3250);
PAINT MONO (2600 3250);
DISPLAY INVISIBLE (2600 3250);
FORCEPROP 2 LAST BOM_COST SM_CONTROLLER
J 0
(3375 3300);
PAINT MONO (3375 3300);
DISPLAY INVISIBLE (3375 3300);
FORCEPROP 2 LAST PATH I25
J 0
(2925 3300);
DISPLAY 1.021277 (2925 3300);
PAINT ORANGE (2925 3300);
DISPLAY INVISIBLE (2925 3300);
FORCEADD PVCCIO_CPU1..1
(2225 2875);
FORCEPROP 3 LASTPIN (2225 2825) SIG_NAME PVCCIO_CPU1\g
J 0
(2235 2835);
DISPLAY 0.659574 (2235 2835);
PAINT MONO (2235 2835);
DISPLAY INVISIBLE (2235 2835);
FORCEPROP 1 LAST HDL_POWER PVCCIO_CPU1
J 1
(2225 2925);
DISPLAY 0.872340 (2225 2925);
PAINT GREEN (2225 2925);
DISPLAY INVISIBLE (2225 2925);
FORCEPROP 1 LAST BODY_TYPE PLUMBING
J 0
(2180 2832);
DISPLAY 0.340426 (2180 2832);
PAINT GREEN (2180 2832);
DISPLAY INVISIBLE (2180 2832);
FORCEPROP 1 LAST VOLTAGE 1.1V
J 0
(2180 2832);
DISPLAY 0.340426 (2180 2832);
PAINT SKYBLUE (2180 2832);
DISPLAY INVISIBLE (2180 2832);
FORCEPROP 2 LAST CDS_LIB mstr_symbols
J 0
(2225 2875);
PAINT ORANGE (2225 2875);
DISPLAY INVISIBLE (2225 2875);
FORCEPROP 1 LAST PATH I26
J 0
(2275 2900);
DISPLAY 0.872340 (2275 2900);
PAINT AQUA (2275 2900);
DISPLAY INVISIBLE (2275 2900);
FORCEADD CAP_A..1
(2225 2700);
FORCEPROP 1 LAST LOCATION C4G22
J 0
(2275 2800);
DISPLAY 0.617021 (2275 2800);
PAINT AQUA (2275 2800);
FORCEPROP 1 LAST PART_NUMBER A36096-030
J 0
(2275 2550);
DISPLAY 0.617021 (2275 2550);
PAINT BLUE (2275 2550);
FORCEPROP 1 LAST VALUE 0.1UF
J 0
(2275 2750);
DISPLAY 0.617021 (2275 2750);
PAINT SKYBLUE (2275 2750);
FORCEPROP 1 LAST TOLERANCE 10%
J 0
(2275 2650);
DISPLAY 0.617021 (2275 2650);
PAINT SKYBLUE (2275 2650);
FORCEPROP 1 LAST PACK_TYPE 0402V
J 0
(2275 2500);
DISPLAY 0.617021 (2275 2500);
PAINT SKYBLUE (2275 2500);
FORCEPROP 1 LAST VOLTAGE 16V
J 0
(2275 2700);
DISPLAY 0.617021 (2275 2700);
PAINT SKYBLUE (2275 2700);
FORCEPROP 1 LAST MATERIAL X7R
J 0
(2275 2600);
DISPLAY 0.617021 (2275 2600);
PAINT SKYBLUE (2275 2600);
FORCEPROP 1 LASTPIN (2225 2800) $PN 1
J 0
(2235 2780);
DISPLAY 0.617021 (2235 2780);
PAINT MONO (2235 2780);
FORCEPROP 1 LASTPIN (2225 2600) $PN 2
J 0
(2235 2580);
DISPLAY 0.617021 (2235 2580);
PAINT MONO (2235 2580);
FORCEPROP 1 LAST PATH I27
J 0
(2275 2850);
DISPLAY 0.978723 (2275 2850);
PAINT WHITE (2275 2850);
DISPLAY INVISIBLE (2275 2850);
FORCEPROP 2 LAST ROOM MEM
J 0
(2275 2825);
PAINT MONO (2275 2825);
DISPLAY INVISIBLE (2275 2825);
FORCEPROP 2 LAST CDS_LOCATION C4G22
J 0
(2275 2800);
DISPLAY 0.617021 (2275 2800);
PAINT AQUA (2275 2800);
DISPLAY INVISIBLE (2275 2800);
FORCEPROP 2 LAST SIGNAL_MODEL DEFAULT_CAPACITOR_100000pF_2_1
J 0
(2275 2925);
DISPLAY 1.617021 (2275 2925);
PAINT MONO (2275 2925);
DISPLAY INVISIBLE (2275 2925);
FORCEPROP 2 LAST CD_SEC 1
J 0
(2275 2925);
DISPLAY 1.617021 (2275 2925);
PAINT MONO (2275 2925);
DISPLAY INVISIBLE (2275 2925);
FORCEPROP 2 LAST BOM_COST SM_CONTROLLER
J 0
(2275 2850);
DISPLAY 2.170213 (2275 2850);
PAINT ORANGE (2275 2850);
DISPLAY INVISIBLE (2275 2850);
FORCEPROP 2 LAST CDS_LIB dev_discrete
J 0
(2225 2700);
PAINT ORANGE (2225 2700);
DISPLAY INVISIBLE (2225 2700);
FORCEPROP 2 LAST CDS_SEC 1
J 0
(2275 2900);
DISPLAY 1.404255 (2275 2900);
PAINT ORANGE (2275 2900);
DISPLAY INVISIBLE (2275 2900);
FORCEPROP 2 LAST $SEC 1
J 0
(2275 2900);
DISPLAY 0.936170 (2275 2900);
PAINT MONO (2275 2900);
DISPLAY INVISIBLE (2275 2900);
FORCEADD GND..1
(2225 2450);
FORCEPROP 3 LASTPIN (2225 2500) SIG_NAME GND\g
J 0
(2235 2510);
DISPLAY 0.659574 (2235 2510);
PAINT MONO (2235 2510);
DISPLAY INVISIBLE (2235 2510);
FORCEPROP 1 LAST HDL_POWER GND
J 0
(2225 2600);
DISPLAY 2.361702 (2225 2600);
PAINT GREEN (2225 2600);
DISPLAY INVISIBLE (2225 2600);
FORCEPROP 1 LAST BODY_TYPE PLUMBING
J 0
(2180 2407);
DISPLAY 0.340426 (2180 2407);
PAINT GREEN (2180 2407);
DISPLAY INVISIBLE (2180 2407);
FORCEPROP 1 LAST VOLTAGE 0
J 0
(2225 2450);
PAINT SKYBLUE (2225 2450);
DISPLAY INVISIBLE (2225 2450);
FORCEPROP 2 LAST BOM_COST SM_CONTROLLER
J 0
(1825 2525);
DISPLAY 1.617021 (1825 2525);
PAINT ORANGE (1825 2525);
DISPLAY INVISIBLE (1825 2525);
FORCEPROP 2 LAST CDS_LIB mstr_symbols
J 0
(2225 2450);
PAINT MONO (2225 2450);
DISPLAY INVISIBLE (2225 2450);
FORCEPROP 1 LAST SIZE 1B
J 0
(2300 2400);
DISPLAY 2.361702 (2300 2400);
PAINT GREEN (2300 2400);
DISPLAY INVISIBLE (2300 2400);
FORCEPROP 1 LAST PATH I28
J 0
(2300 2450);
DISPLAY 0.872340 (2300 2450);
PAINT AQUA (2300 2450);
DISPLAY INVISIBLE (2300 2450);
FORCEPROP 2 LAST ROOM SMB
J 0
(2125 2525);
PAINT MONO (2125 2525);
DISPLAY INVISIBLE (2125 2525);
FORCEADD OFFPAGE..3
(2625 2100);
FORCEPROP 2 LAST $XR0 77 
J 0
(2839 2100);
DISPLAY 0.638298 (2839 2100);
PAINT MONO (2839 2100);
FORCEPROP 2 LAST $XR1 78 
J 0
(2929 2100);
DISPLAY 0.638298 (2929 2100);
PAINT MONO (2929 2100);
FORCEPROP 2 LAST $XR2 79 
J 0
(3019 2100);
DISPLAY 0.638298 (3019 2100);
PAINT MONO (3019 2100);
FORCEPROP 2 LAST $XR3 80 
J 0
(3109 2100);
DISPLAY 0.638298 (3109 2100);
PAINT MONO (3109 2100);
FORCEPROP 2 LAST $XR4 81 
J 0
(3199 2100);
DISPLAY 0.638298 (3199 2100);
PAINT MONO (3199 2100);
FORCEPROP 2 LAST $XR5 82 
J 0
(3289 2100);
DISPLAY 0.638298 (3289 2100);
PAINT MONO (3289 2100);
FORCEPROP 1 LAST COMMENT_BODY TRUE
J 0
(2575 2000);
DISPLAY 1.872340 (2575 2000);
PAINT GREEN (2575 2000);
DISPLAY INVISIBLE (2575 2000);
FORCEPROP 1 LAST OFFPAGE TRUE
J 0
(2950 1975);
PAINT GREEN (2950 1975);
DISPLAY INVISIBLE (2950 1975);
FORCEPROP 2 LAST CDS_LIB mstr_standard
J 0
(2625 2100);
PAINT MONO (2625 2100);
DISPLAY INVISIBLE (2625 2100);
FORCEPROP 2 LAST BOM_COST SM_CONTROLLER
J 0
(3300 2150);
PAINT MONO (3300 2150);
DISPLAY INVISIBLE (3300 2150);
FORCEPROP 2 LAST ROOM SMB
J 0
(3300 2150);
PAINT MONO (3300 2150);
DISPLAY INVISIBLE (3300 2150);
FORCEPROP 2 LAST PATH I29
J 0
(2950 2150);
DISPLAY 1.021277 (2950 2150);
PAINT ORANGE (2950 2150);
DISPLAY INVISIBLE (2950 2150);
FORCEADD GND..1
(1900 4675);
FORCEPROP 3 LASTPIN (1900 4725) SIG_NAME GND\g
J 0
(1910 4735);
DISPLAY 0.659574 (1910 4735);
PAINT MONO (1910 4735);
DISPLAY INVISIBLE (1910 4735);
FORCEPROP 1 LAST HDL_POWER GND
J 0
(1900 4825);
DISPLAY 2.361702 (1900 4825);
PAINT GREEN (1900 4825);
DISPLAY INVISIBLE (1900 4825);
FORCEPROP 1 LAST BODY_TYPE PLUMBING
J 0
(1855 4632);
DISPLAY 0.340426 (1855 4632);
PAINT GREEN (1855 4632);
DISPLAY INVISIBLE (1855 4632);
FORCEPROP 1 LAST VOLTAGE 0
J 0
(1900 4675);
PAINT SKYBLUE (1900 4675);
DISPLAY INVISIBLE (1900 4675);
FORCEPROP 1 LAST SIZE 1B
J 0
(1975 4625);
DISPLAY 2.361702 (1975 4625);
PAINT GREEN (1975 4625);
DISPLAY INVISIBLE (1975 4625);
FORCEPROP 2 LAST CDS_LIB mstr_symbols
J 0
(1900 4675);
PAINT MONO (1900 4675);
DISPLAY INVISIBLE (1900 4675);
FORCEPROP 2 LAST BOM_COST SM_CONTROLLER
J 0
(1500 4750);
DISPLAY 1.617021 (1500 4750);
PAINT ORANGE (1500 4750);
DISPLAY INVISIBLE (1500 4750);
FORCEPROP 1 LAST PATH I3
J 0
(1975 4675);
DISPLAY 0.872340 (1975 4675);
PAINT AQUA (1975 4675);
DISPLAY INVISIBLE (1975 4675);
FORCEPROP 2 LAST ROOM SMB
J 0
(1800 4750);
PAINT MONO (1800 4750);
DISPLAY INVISIBLE (1800 4750);
FORCEADD OFFPAGE..2
(2625 2150);
FORCEPROP 2 LAST $XR0 77 
J 0
(2814 2150);
DISPLAY 0.638298 (2814 2150);
PAINT MONO (2814 2150);
FORCEPROP 2 LAST $XR1 78 
J 0
(2904 2150);
DISPLAY 0.638298 (2904 2150);
PAINT MONO (2904 2150);
FORCEPROP 2 LAST $XR2 79 
J 0
(2994 2150);
DISPLAY 0.638298 (2994 2150);
PAINT MONO (2994 2150);
FORCEPROP 2 LAST $XR3 80 
J 0
(3084 2150);
DISPLAY 0.638298 (3084 2150);
PAINT MONO (3084 2150);
FORCEPROP 2 LAST $XR4 81 
J 0
(3174 2150);
DISPLAY 0.638298 (3174 2150);
PAINT MONO (3174 2150);
FORCEPROP 2 LAST $XR5 82 
J 0
(3264 2150);
DISPLAY 0.638298 (3264 2150);
PAINT MONO (3264 2150);
FORCEPROP 1 LAST COMMENT_BODY TRUE
J 0
(2580 2055);
DISPLAY 0.872340 (2580 2055);
PAINT GREEN (2580 2055);
DISPLAY INVISIBLE (2580 2055);
FORCEPROP 1 LAST OFFPAGE TRUE
J 0
(2950 2025);
PAINT GREEN (2950 2025);
DISPLAY INVISIBLE (2950 2025);
FORCEPROP 2 LAST CDS_LIB mstr_standard
J 0
(2625 2150);
PAINT ORANGE (2625 2150);
DISPLAY INVISIBLE (2625 2150);
FORCEPROP 2 LAST BOM_COST SM_CONTROLLER
J 0
(2950 2200);
PAINT MONO (2950 2200);
DISPLAY INVISIBLE (2950 2200);
FORCEPROP 2 LAST PATH I30
J 0
(2925 2200);
DISPLAY 1.021277 (2925 2200);
PAINT ORANGE (2925 2200);
DISPLAY INVISIBLE (2925 2200);
FORCEADD PVPP_DEF..1
(1625 3950);
FORCEPROP 3 LASTPIN (1625 3900) SIG_NAME PVPP_DEF\g
J 0
(1635 3910);
DISPLAY 0.659574 (1635 3910);
PAINT MONO (1635 3910);
DISPLAY INVISIBLE (1635 3910);
FORCEPROP 1 LAST HDL_POWER PVPP_DEF
J 1
(1625 4000);
DISPLAY 0.872340 (1625 4000);
PAINT GREEN (1625 4000);
DISPLAY INVISIBLE (1625 4000);
FORCEPROP 1 LAST BODY_TYPE PLUMBING
J 0
(1580 3907);
DISPLAY 0.340426 (1580 3907);
PAINT GREEN (1580 3907);
DISPLAY INVISIBLE (1580 3907);
FORCEPROP 1 LAST VOLTAGE 2.5V
J 0
(1580 3907);
DISPLAY 0.340426 (1580 3907);
PAINT SKYBLUE (1580 3907);
DISPLAY INVISIBLE (1580 3907);
FORCEPROP 2 LAST CDS_LIB mstr_symbols
J 0
(1625 3950);
PAINT ORANGE (1625 3950);
DISPLAY INVISIBLE (1625 3950);
FORCEPROP 1 LAST PATH I31
J 0
(1675 3975);
DISPLAY 0.872340 (1675 3975);
PAINT AQUA (1675 3975);
DISPLAY INVISIBLE (1675 3975);
FORCEADD CAP_A..1
(1625 3750);
FORCEPROP 1 LAST LOCATION C7E2
J 0
(1675 3850);
DISPLAY 0.617021 (1675 3850);
PAINT AQUA (1675 3850);
FORCEPROP 1 LAST PART_NUMBER A36096-030
J 0
(1675 3600);
DISPLAY 0.617021 (1675 3600);
PAINT BLUE (1675 3600);
FORCEPROP 1 LAST VALUE 0.1UF
J 0
(1675 3800);
DISPLAY 0.617021 (1675 3800);
PAINT SKYBLUE (1675 3800);
FORCEPROP 1 LAST TOLERANCE 10%
J 0
(1675 3700);
DISPLAY 0.617021 (1675 3700);
PAINT SKYBLUE (1675 3700);
FORCEPROP 1 LAST PACK_TYPE 0402V
J 0
(1675 3550);
DISPLAY 0.617021 (1675 3550);
PAINT SKYBLUE (1675 3550);
FORCEPROP 1 LAST VOLTAGE 16V
J 0
(1675 3750);
DISPLAY 0.617021 (1675 3750);
PAINT SKYBLUE (1675 3750);
FORCEPROP 1 LAST MATERIAL X7R
J 0
(1675 3650);
DISPLAY 0.617021 (1675 3650);
PAINT SKYBLUE (1675 3650);
FORCEPROP 1 LASTPIN (1625 3850) $PN 1
J 0
(1635 3830);
DISPLAY 0.617021 (1635 3830);
PAINT MONO (1635 3830);
FORCEPROP 1 LASTPIN (1625 3650) $PN 2
J 0
(1635 3630);
DISPLAY 0.617021 (1635 3630);
PAINT MONO (1635 3630);
FORCEPROP 1 LAST PATH I32
J 0
(1675 3900);
DISPLAY 0.978723 (1675 3900);
PAINT WHITE (1675 3900);
DISPLAY INVISIBLE (1675 3900);
FORCEPROP 2 LAST ROOM MEM
J 0
(1675 3875);
PAINT MONO (1675 3875);
DISPLAY INVISIBLE (1675 3875);
FORCEPROP 2 LAST CDS_LOCATION C7E2
J 0
(1675 3850);
DISPLAY 0.617021 (1675 3850);
PAINT AQUA (1675 3850);
DISPLAY INVISIBLE (1675 3850);
FORCEPROP 2 LAST CD_SEC 1
J 0
(1675 3975);
DISPLAY 1.617021 (1675 3975);
PAINT MONO (1675 3975);
DISPLAY INVISIBLE (1675 3975);
FORCEPROP 2 LAST SIGNAL_MODEL DEFAULT_CAPACITOR_100000pF_2_1
J 0
(1675 3975);
DISPLAY 1.617021 (1675 3975);
PAINT MONO (1675 3975);
DISPLAY INVISIBLE (1675 3975);
FORCEPROP 2 LAST BOM_COST SM_CONTROLLER
J 0
(1675 3900);
DISPLAY 2.170213 (1675 3900);
PAINT ORANGE (1675 3900);
DISPLAY INVISIBLE (1675 3900);
FORCEPROP 2 LAST CDS_LIB dev_discrete
J 0
(1625 3750);
PAINT ORANGE (1625 3750);
DISPLAY INVISIBLE (1625 3750);
FORCEPROP 2 LAST CDS_SEC 1
J 0
(1675 3950);
DISPLAY 1.404255 (1675 3950);
PAINT ORANGE (1675 3950);
DISPLAY INVISIBLE (1675 3950);
FORCEPROP 2 LAST $SEC 1
J 0
(1675 3950);
DISPLAY 0.936170 (1675 3950);
PAINT MONO (1675 3950);
DISPLAY INVISIBLE (1675 3950);
FORCEADD GND..1
(1625 3500);
FORCEPROP 3 LASTPIN (1625 3550) SIG_NAME GND\g
J 0
(1635 3560);
DISPLAY 0.659574 (1635 3560);
PAINT MONO (1635 3560);
DISPLAY INVISIBLE (1635 3560);
FORCEPROP 1 LAST HDL_POWER GND
J 0
(1625 3650);
DISPLAY 2.361702 (1625 3650);
PAINT GREEN (1625 3650);
DISPLAY INVISIBLE (1625 3650);
FORCEPROP 1 LAST BODY_TYPE PLUMBING
J 0
(1580 3457);
DISPLAY 0.340426 (1580 3457);
PAINT GREEN (1580 3457);
DISPLAY INVISIBLE (1580 3457);
FORCEPROP 1 LAST VOLTAGE 0
J 0
(1625 3500);
PAINT SKYBLUE (1625 3500);
DISPLAY INVISIBLE (1625 3500);
FORCEPROP 1 LAST SIZE 1B
J 0
(1700 3450);
DISPLAY 2.361702 (1700 3450);
PAINT GREEN (1700 3450);
DISPLAY INVISIBLE (1700 3450);
FORCEPROP 2 LAST CDS_LIB mstr_symbols
J 0
(1625 3500);
PAINT MONO (1625 3500);
DISPLAY INVISIBLE (1625 3500);
FORCEPROP 1 LAST PATH I33
J 0
(1700 3500);
DISPLAY 0.872340 (1700 3500);
PAINT AQUA (1700 3500);
DISPLAY INVISIBLE (1700 3500);
FORCEPROP 2 LAST ROOM SMB
J 0
(1525 3575);
PAINT MONO (1525 3575);
DISPLAY INVISIBLE (1525 3575);
FORCEADD RES..1
(1600 3250);
FORCEPROP 2 LASTPIN (1700 3250) SIG_NAME SMB_DDR_DEF_VPP_SDA
J 0
(1890 3260);
DISPLAY 0.617021 (1890 3260);
PAINT ORANGE (1890 3260);
FORCEPROP 1 LAST LOCATION R3R9
J 0
(1300 3200);
DISPLAY 0.617021 (1300 3200);
PAINT AQUA (1300 3200);
FORCEPROP 1 LAST PART_NUMBER G21796-173
J 0
(1875 3100);
DISPLAY 0.617021 (1875 3100);
PAINT BLUE (1875 3100);
FORCEPROP 1 LAST VALUE 20.0
J 2
(1550 3200);
DISPLAY 0.617021 (1550 3200);
PAINT SKYBLUE (1550 3200);
FORCEPROP 1 LAST TOLERANCE 1%
J 0
(1850 3200);
DISPLAY 0.617021 (1850 3200);
PAINT SKYBLUE (1850 3200);
FORCEPROP 1 LAST PACK_TYPE 0402
J 0
(1650 3200);
DISPLAY 0.617021 (1650 3200);
PAINT SKYBLUE (1650 3200);
FORCEPROP 1 LAST MATERIAL CHIP
J 0
(2050 3150);
DISPLAY 0.617021 (2050 3150);
PAINT SKYBLUE (2050 3150);
FORCEPROP 1 LAST WATTAGE 1/16W
J 2
(2025 3150);
DISPLAY 0.617021 (2025 3150);
PAINT SKYBLUE (2025 3150);
FORCEPROP 1 LASTPIN (1700 3250) $PN 2
J 0
(1662 3262);
DISPLAY 0.617021 (1662 3262);
PAINT MONO (1662 3262);
FORCEPROP 1 LASTPIN (1500 3250) $PN 1
J 0
(1512 3262);
DISPLAY 0.617021 (1512 3262);
PAINT MONO (1512 3262);
FORCEPROP 2 LAST CDS_LIB mstr_discrete
J 0
(1600 3250);
PAINT ORANGE (1600 3250);
DISPLAY INVISIBLE (1600 3250);
FORCEPROP 2 LAST CDS_SEC 1
J 0
(1550 3450);
DISPLAY 1.404255 (1550 3450);
PAINT ORANGE (1550 3450);
DISPLAY INVISIBLE (1550 3450);
FORCEPROP 2 LAST $SEC 1
J 0
(1550 3450);
DISPLAY 0.936170 (1550 3450);
PAINT MONO (1550 3450);
DISPLAY INVISIBLE (1550 3450);
FORCEPROP 2 LAST CDS_LOCATION R3R9
J 0
(1300 3200);
DISPLAY 0.617021 (1300 3200);
PAINT AQUA (1300 3200);
DISPLAY INVISIBLE (1300 3200);
FORCEPROP 1 LAST PATH I34
J 0
(1550 3400);
DISPLAY 0.978723 (1550 3400);
PAINT WHITE (1550 3400);
DISPLAY INVISIBLE (1550 3400);
FORCEPROP 2 LAST ROOM MEM
J 0
(1800 3250);
DISPLAY 1.404255 (1800 3250);
PAINT ORANGE (1800 3250);
DISPLAY INVISIBLE (1800 3250);
FORCEADD RES..1
(1600 3300);
FORCEPROP 1 LAST LOCATION R3R8
J 0
(1550 3375);
DISPLAY 0.617021 (1550 3375);
PAINT AQUA (1550 3375);
FORCEPROP 1 LAST PART_NUMBER G21796-173
J 0
(1850 3450);
DISPLAY 0.617021 (1850 3450);
PAINT BLUE (1850 3450);
FORCEPROP 1 LAST VALUE 20.0
J 2
(1550 3350);
DISPLAY 0.617021 (1550 3350);
PAINT SKYBLUE (1550 3350);
FORCEPROP 1 LAST TOLERANCE 1%
J 0
(1850 3350);
DISPLAY 0.617021 (1850 3350);
PAINT SKYBLUE (1850 3350);
FORCEPROP 1 LAST PACK_TYPE 0402
J 0
(1650 3350);
DISPLAY 0.617021 (1650 3350);
PAINT SKYBLUE (1650 3350);
FORCEPROP 1 LAST MATERIAL CHIP
J 0
(2025 3400);
DISPLAY 0.617021 (2025 3400);
PAINT SKYBLUE (2025 3400);
FORCEPROP 1 LAST WATTAGE 1/16W
J 2
(2000 3400);
DISPLAY 0.617021 (2000 3400);
PAINT SKYBLUE (2000 3400);
FORCEPROP 1 LASTPIN (1700 3300) $PN 2
J 0
(1662 3312);
DISPLAY 0.617021 (1662 3312);
PAINT MONO (1662 3312);
FORCEPROP 1 LASTPIN (1500 3300) $PN 1
J 0
(1512 3312);
DISPLAY 0.617021 (1512 3312);
PAINT MONO (1512 3312);
FORCEPROP 2 LAST CDS_LIB mstr_discrete
J 0
(1600 3300);
PAINT ORANGE (1600 3300);
DISPLAY INVISIBLE (1600 3300);
FORCEPROP 2 LAST CDS_SEC 1
J 0
(1550 3500);
DISPLAY 1.404255 (1550 3500);
PAINT ORANGE (1550 3500);
DISPLAY INVISIBLE (1550 3500);
FORCEPROP 2 LAST $SEC 1
J 0
(1550 3500);
DISPLAY 0.936170 (1550 3500);
PAINT MONO (1550 3500);
DISPLAY INVISIBLE (1550 3500);
FORCEPROP 2 LAST CDS_LOCATION R3R8
J 0
(1550 3375);
DISPLAY 0.617021 (1550 3375);
PAINT AQUA (1550 3375);
DISPLAY INVISIBLE (1550 3375);
FORCEPROP 1 LAST PATH I35
J 0
(1550 3450);
DISPLAY 0.978723 (1550 3450);
PAINT WHITE (1550 3450);
DISPLAY INVISIBLE (1550 3450);
FORCEPROP 2 LAST ROOM MEM
J 0
(1800 3400);
DISPLAY 1.404255 (1800 3400);
PAINT ORANGE (1800 3400);
DISPLAY INVISIBLE (1800 3400);
FORCEADD PVPP_GHJ..1
(1650 2875);
FORCEPROP 3 LASTPIN (1650 2825) SIG_NAME PVPP_GHJ\g
J 0
(1660 2835);
DISPLAY 0.659574 (1660 2835);
PAINT MONO (1660 2835);
DISPLAY INVISIBLE (1660 2835);
FORCEPROP 1 LAST HDL_POWER PVPP_GHJ
J 1
(1650 2925);
DISPLAY 0.872340 (1650 2925);
PAINT GREEN (1650 2925);
DISPLAY INVISIBLE (1650 2925);
FORCEPROP 1 LAST BODY_TYPE PLUMBING
J 0
(1605 2832);
DISPLAY 0.340426 (1605 2832);
PAINT GREEN (1605 2832);
DISPLAY INVISIBLE (1605 2832);
FORCEPROP 1 LAST VOLTAGE 2.5V
J 0
(1605 2832);
DISPLAY 0.340426 (1605 2832);
PAINT SKYBLUE (1605 2832);
DISPLAY INVISIBLE (1605 2832);
FORCEPROP 2 LAST BOM_COST SM_CONTROLLER
J 0
(1650 2975);
DISPLAY 1.617021 (1650 2975);
PAINT ORANGE (1650 2975);
DISPLAY INVISIBLE (1650 2975);
FORCEPROP 2 LAST CDS_LIB mstr_symbols
J 0
(1650 2875);
PAINT ORANGE (1650 2875);
DISPLAY INVISIBLE (1650 2875);
FORCEPROP 1 LAST PATH I39
J 0
(1700 2900);
DISPLAY 0.872340 (1700 2900);
PAINT AQUA (1700 2900);
DISPLAY INVISIBLE (1700 2900);
FORCEPROP 2 LAST ROOM SMB
J 0
(1650 2950);
PAINT MONO (1650 2950);
DISPLAY INVISIBLE (1650 2950);
FORCEADD OFFPAGE..2
(2600 4350);
FORCEPROP 2 LAST $XR0 43 
J 0
(2789 4350);
DISPLAY 0.638298 (2789 4350);
PAINT MONO (2789 4350);
FORCEPROP 2 LAST $XR1 44 
J 0
(2879 4350);
DISPLAY 0.638298 (2879 4350);
PAINT MONO (2879 4350);
FORCEPROP 2 LAST $XR2 45 
J 0
(2969 4350);
DISPLAY 0.638298 (2969 4350);
PAINT MONO (2969 4350);
FORCEPROP 2 LAST $XR3 46 
J 0
(3059 4350);
DISPLAY 0.638298 (3059 4350);
PAINT MONO (3059 4350);
FORCEPROP 2 LAST $XR4 47 
J 0
(3149 4350);
DISPLAY 0.638298 (3149 4350);
PAINT MONO (3149 4350);
FORCEPROP 2 LAST $XR5 48 
J 0
(3239 4350);
DISPLAY 0.638298 (3239 4350);
PAINT MONO (3239 4350);
FORCEPROP 1 LAST COMMENT_BODY TRUE
J 0
(2555 4255);
DISPLAY 0.872340 (2555 4255);
PAINT GREEN (2555 4255);
DISPLAY INVISIBLE (2555 4255);
FORCEPROP 1 LAST OFFPAGE TRUE
J 0
(2925 4225);
PAINT GREEN (2925 4225);
DISPLAY INVISIBLE (2925 4225);
FORCEPROP 2 LAST CDS_LIB mstr_standard
J 0
(2600 4350);
PAINT ORANGE (2600 4350);
DISPLAY INVISIBLE (2600 4350);
FORCEPROP 2 LAST BOM_COST SM_CONTROLLER
J 0
(2925 4400);
PAINT MONO (2925 4400);
DISPLAY INVISIBLE (2925 4400);
FORCEPROP 2 LAST PATH I4
J 0
(2900 4400);
DISPLAY 1.021277 (2900 4400);
PAINT ORANGE (2900 4400);
DISPLAY INVISIBLE (2900 4400);
FORCEADD GND..1
(1650 2425);
FORCEPROP 3 LASTPIN (1650 2475) SIG_NAME GND\g
J 0
(1660 2485);
DISPLAY 0.659574 (1660 2485);
PAINT MONO (1660 2485);
DISPLAY INVISIBLE (1660 2485);
FORCEPROP 1 LAST HDL_POWER GND
J 0
(1650 2575);
DISPLAY 2.361702 (1650 2575);
PAINT GREEN (1650 2575);
DISPLAY INVISIBLE (1650 2575);
FORCEPROP 1 LAST BODY_TYPE PLUMBING
J 0
(1605 2382);
DISPLAY 0.340426 (1605 2382);
PAINT GREEN (1605 2382);
DISPLAY INVISIBLE (1605 2382);
FORCEPROP 1 LAST VOLTAGE 0
J 0
(1650 2425);
PAINT SKYBLUE (1650 2425);
DISPLAY INVISIBLE (1650 2425);
FORCEPROP 1 LAST SIZE 1B
J 0
(1725 2375);
DISPLAY 2.361702 (1725 2375);
PAINT GREEN (1725 2375);
DISPLAY INVISIBLE (1725 2375);
FORCEPROP 2 LAST CDS_LIB mstr_symbols
J 0
(1650 2425);
PAINT MONO (1650 2425);
DISPLAY INVISIBLE (1650 2425);
FORCEPROP 2 LAST BOM_COST SM_CONTROLLER
J 0
(1250 2500);
DISPLAY 1.617021 (1250 2500);
PAINT ORANGE (1250 2500);
DISPLAY INVISIBLE (1250 2500);
FORCEPROP 1 LAST PATH I40
J 0
(1725 2425);
DISPLAY 0.872340 (1725 2425);
PAINT AQUA (1725 2425);
DISPLAY INVISIBLE (1725 2425);
FORCEPROP 2 LAST ROOM SMB
J 0
(1550 2500);
PAINT MONO (1550 2500);
DISPLAY INVISIBLE (1550 2500);
FORCEADD CAP_A..1
(1650 2675);
FORCEPROP 1 LAST LOCATION C4G25
J 0
(1700 2775);
DISPLAY 0.617021 (1700 2775);
PAINT AQUA (1700 2775);
FORCEPROP 1 LAST PART_NUMBER A36096-030
J 0
(1700 2525);
DISPLAY 0.617021 (1700 2525);
PAINT BLUE (1700 2525);
FORCEPROP 1 LAST VALUE 0.1UF
J 0
(1700 2725);
DISPLAY 0.617021 (1700 2725);
PAINT SKYBLUE (1700 2725);
FORCEPROP 1 LAST TOLERANCE 10%
J 0
(1700 2625);
DISPLAY 0.617021 (1700 2625);
PAINT SKYBLUE (1700 2625);
FORCEPROP 1 LAST PACK_TYPE 0402V
J 0
(1700 2475);
DISPLAY 0.617021 (1700 2475);
PAINT SKYBLUE (1700 2475);
FORCEPROP 1 LAST VOLTAGE 16V
J 0
(1700 2675);
DISPLAY 0.617021 (1700 2675);
PAINT SKYBLUE (1700 2675);
FORCEPROP 1 LAST MATERIAL X7R
J 0
(1700 2575);
DISPLAY 0.617021 (1700 2575);
PAINT SKYBLUE (1700 2575);
FORCEPROP 1 LASTPIN (1650 2775) $PN 1
J 0
(1660 2755);
DISPLAY 0.617021 (1660 2755);
PAINT MONO (1660 2755);
FORCEPROP 1 LASTPIN (1650 2575) $PN 2
J 0
(1660 2555);
DISPLAY 0.617021 (1660 2555);
PAINT MONO (1660 2555);
FORCEPROP 1 LAST PATH I41
J 0
(1700 2825);
DISPLAY 0.978723 (1700 2825);
PAINT WHITE (1700 2825);
DISPLAY INVISIBLE (1700 2825);
FORCEPROP 2 LAST ROOM MEM
J 0
(1700 2800);
PAINT MONO (1700 2800);
DISPLAY INVISIBLE (1700 2800);
FORCEPROP 2 LAST CDS_LOCATION C4G25
J 0
(1700 2775);
DISPLAY 0.617021 (1700 2775);
PAINT AQUA (1700 2775);
DISPLAY INVISIBLE (1700 2775);
FORCEPROP 2 LAST BOM_COST SM_CONTROLLER
J 0
(1700 2825);
DISPLAY 2.170213 (1700 2825);
PAINT ORANGE (1700 2825);
DISPLAY INVISIBLE (1700 2825);
FORCEPROP 2 LAST SIGNAL_MODEL DEFAULT_CAPACITOR_100000pF_2_1
J 0
(1700 2900);
DISPLAY 1.617021 (1700 2900);
PAINT MONO (1700 2900);
DISPLAY INVISIBLE (1700 2900);
FORCEPROP 2 LAST CD_SEC 1
J 0
(1700 2900);
DISPLAY 1.617021 (1700 2900);
PAINT MONO (1700 2900);
DISPLAY INVISIBLE (1700 2900);
FORCEPROP 2 LAST CDS_LIB dev_discrete
J 0
(1650 2675);
PAINT ORANGE (1650 2675);
DISPLAY INVISIBLE (1650 2675);
FORCEPROP 2 LAST CDS_SEC 1
J 0
(1700 2875);
DISPLAY 1.404255 (1700 2875);
PAINT ORANGE (1700 2875);
DISPLAY INVISIBLE (1700 2875);
FORCEPROP 2 LAST $SEC 1
J 0
(1700 2875);
DISPLAY 0.936170 (1700 2875);
PAINT MONO (1700 2875);
DISPLAY INVISIBLE (1700 2875);
FORCEADD RES..1
(1600 2150);
FORCEPROP 1 LAST LOCATION R6U13
J 0
(1550 2225);
DISPLAY 0.617021 (1550 2225);
PAINT AQUA (1550 2225);
FORCEPROP 1 LAST PART_NUMBER G21796-173
J 0
(1825 2300);
DISPLAY 0.617021 (1825 2300);
PAINT BLUE (1825 2300);
FORCEPROP 1 LAST VALUE 20.0
J 2
(1550 2200);
DISPLAY 0.617021 (1550 2200);
PAINT SKYBLUE (1550 2200);
FORCEPROP 1 LAST TOLERANCE 1%
J 0
(1850 2200);
DISPLAY 0.617021 (1850 2200);
PAINT SKYBLUE (1850 2200);
FORCEPROP 1 LAST PACK_TYPE 0402
J 0
(1650 2200);
DISPLAY 0.617021 (1650 2200);
PAINT SKYBLUE (1650 2200);
FORCEPROP 1 LAST MATERIAL CHIP
J 0
(2000 2250);
DISPLAY 0.617021 (2000 2250);
PAINT SKYBLUE (2000 2250);
FORCEPROP 1 LAST WATTAGE 1/16W
J 2
(1975 2250);
DISPLAY 0.617021 (1975 2250);
PAINT SKYBLUE (1975 2250);
FORCEPROP 1 LASTPIN (1700 2150) $PN 2
J 0
(1662 2162);
DISPLAY 0.617021 (1662 2162);
PAINT MONO (1662 2162);
FORCEPROP 1 LASTPIN (1500 2150) $PN 1
J 0
(1512 2162);
DISPLAY 0.617021 (1512 2162);
PAINT MONO (1512 2162);
FORCEPROP 2 LAST CDS_LIB mstr_discrete
J 0
(1600 2150);
PAINT ORANGE (1600 2150);
DISPLAY INVISIBLE (1600 2150);
FORCEPROP 2 LAST CDS_SEC 1
J 0
(1550 2350);
DISPLAY 1.404255 (1550 2350);
PAINT ORANGE (1550 2350);
DISPLAY INVISIBLE (1550 2350);
FORCEPROP 2 LAST $SEC 1
J 0
(1550 2350);
DISPLAY 0.936170 (1550 2350);
PAINT MONO (1550 2350);
DISPLAY INVISIBLE (1550 2350);
FORCEPROP 2 LAST CDS_LOCATION R6U13
J 0
(1550 2225);
DISPLAY 0.617021 (1550 2225);
PAINT AQUA (1550 2225);
DISPLAY INVISIBLE (1550 2225);
FORCEPROP 1 LAST PATH I42
J 0
(1550 2300);
DISPLAY 0.978723 (1550 2300);
PAINT WHITE (1550 2300);
DISPLAY INVISIBLE (1550 2300);
FORCEPROP 2 LAST ROOM MEM
J 0
(1800 2250);
DISPLAY 1.404255 (1800 2250);
PAINT ORANGE (1800 2250);
DISPLAY INVISIBLE (1800 2250);
FORCEADD RES..1
(1600 2100);
FORCEPROP 1 LAST LOCATION R6U14
J 0
(1300 2050);
DISPLAY 0.617021 (1300 2050);
PAINT AQUA (1300 2050);
FORCEPROP 1 LAST PART_NUMBER G21796-173
J 0
(1825 1950);
DISPLAY 0.617021 (1825 1950);
PAINT BLUE (1825 1950);
FORCEPROP 1 LAST VALUE 20.0
J 2
(1550 2050);
DISPLAY 0.617021 (1550 2050);
PAINT SKYBLUE (1550 2050);
FORCEPROP 1 LAST TOLERANCE 1%
J 0
(1850 2050);
DISPLAY 0.617021 (1850 2050);
PAINT SKYBLUE (1850 2050);
FORCEPROP 1 LAST PACK_TYPE 0402
J 0
(1650 2050);
DISPLAY 0.617021 (1650 2050);
PAINT SKYBLUE (1650 2050);
FORCEPROP 1 LAST MATERIAL CHIP
J 0
(2000 2000);
DISPLAY 0.617021 (2000 2000);
PAINT SKYBLUE (2000 2000);
FORCEPROP 1 LAST WATTAGE 1/16W
J 2
(1975 2000);
DISPLAY 0.617021 (1975 2000);
PAINT SKYBLUE (1975 2000);
FORCEPROP 1 LASTPIN (1700 2100) $PN 2
J 0
(1662 2112);
DISPLAY 0.617021 (1662 2112);
PAINT MONO (1662 2112);
FORCEPROP 1 LASTPIN (1500 2100) $PN 1
J 0
(1512 2112);
DISPLAY 0.617021 (1512 2112);
PAINT MONO (1512 2112);
FORCEPROP 2 LAST CDS_LIB mstr_discrete
J 0
(1600 2100);
PAINT ORANGE (1600 2100);
DISPLAY INVISIBLE (1600 2100);
FORCEPROP 2 LAST CDS_SEC 1
J 0
(1550 2300);
DISPLAY 1.404255 (1550 2300);
PAINT ORANGE (1550 2300);
DISPLAY INVISIBLE (1550 2300);
FORCEPROP 2 LAST $SEC 1
J 0
(1550 2300);
DISPLAY 0.936170 (1550 2300);
PAINT MONO (1550 2300);
DISPLAY INVISIBLE (1550 2300);
FORCEPROP 2 LAST CDS_LOCATION R6U14
J 0
(1300 2050);
DISPLAY 0.617021 (1300 2050);
PAINT AQUA (1300 2050);
DISPLAY INVISIBLE (1300 2050);
FORCEPROP 1 LAST PATH I43
J 0
(1550 2250);
DISPLAY 0.978723 (1550 2250);
PAINT WHITE (1550 2250);
DISPLAY INVISIBLE (1550 2250);
FORCEPROP 2 LAST ROOM MEM
J 0
(1800 2100);
DISPLAY 1.404255 (1800 2100);
PAINT ORANGE (1800 2100);
DISPLAY INVISIBLE (1800 2100);
FORCEADD CAP_A..1
(2250 1525);
FORCEPROP 1 LAST LOCATION C3B4
J 0
(2300 1625);
DISPLAY 0.617021 (2300 1625);
PAINT AQUA (2300 1625);
FORCEPROP 1 LAST PART_NUMBER A36096-030
J 0
(2300 1375);
DISPLAY 0.617021 (2300 1375);
PAINT BLUE (2300 1375);
FORCEPROP 1 LAST VALUE 0.1UF
J 0
(2300 1575);
DISPLAY 0.617021 (2300 1575);
PAINT SKYBLUE (2300 1575);
FORCEPROP 1 LAST TOLERANCE 10%
J 0
(2300 1475);
DISPLAY 0.617021 (2300 1475);
PAINT SKYBLUE (2300 1475);
FORCEPROP 1 LAST PACK_TYPE 0402V
J 0
(2300 1325);
DISPLAY 0.617021 (2300 1325);
PAINT SKYBLUE (2300 1325);
FORCEPROP 1 LAST VOLTAGE 16V
J 0
(2300 1525);
DISPLAY 0.617021 (2300 1525);
PAINT SKYBLUE (2300 1525);
FORCEPROP 1 LAST MATERIAL X7R
J 0
(2300 1425);
DISPLAY 0.617021 (2300 1425);
PAINT SKYBLUE (2300 1425);
FORCEPROP 1 LASTPIN (2250 1625) $PN 1
J 0
(2260 1605);
DISPLAY 0.617021 (2260 1605);
PAINT MONO (2260 1605);
FORCEPROP 1 LASTPIN (2250 1425) $PN 2
J 0
(2260 1405);
DISPLAY 0.617021 (2260 1405);
PAINT MONO (2260 1405);
FORCEPROP 1 LAST PATH I47
J 0
(2300 1675);
DISPLAY 0.978723 (2300 1675);
PAINT WHITE (2300 1675);
DISPLAY INVISIBLE (2300 1675);
FORCEPROP 2 LAST ROOM MEM
J 0
(2300 1650);
PAINT MONO (2300 1650);
DISPLAY INVISIBLE (2300 1650);
FORCEPROP 2 LAST CDS_LOCATION C3B4
J 0
(2300 1625);
DISPLAY 0.617021 (2300 1625);
PAINT AQUA (2300 1625);
DISPLAY INVISIBLE (2300 1625);
FORCEPROP 2 LAST CD_SEC 1
J 0
(2300 1750);
DISPLAY 1.617021 (2300 1750);
PAINT MONO (2300 1750);
DISPLAY INVISIBLE (2300 1750);
FORCEPROP 2 LAST SIGNAL_MODEL DEFAULT_CAPACITOR_100000pF_2_1
J 0
(2300 1750);
DISPLAY 1.617021 (2300 1750);
PAINT MONO (2300 1750);
DISPLAY INVISIBLE (2300 1750);
FORCEPROP 2 LAST BOM_COST SM_CONTROLLER
J 0
(2300 1675);
DISPLAY 2.170213 (2300 1675);
PAINT ORANGE (2300 1675);
DISPLAY INVISIBLE (2300 1675);
FORCEPROP 2 LAST CDS_LIB dev_discrete
J 0
(2250 1525);
PAINT ORANGE (2250 1525);
DISPLAY INVISIBLE (2250 1525);
FORCEPROP 2 LAST CDS_SEC 1
J 0
(2300 1725);
DISPLAY 1.404255 (2300 1725);
PAINT ORANGE (2300 1725);
DISPLAY INVISIBLE (2300 1725);
FORCEPROP 2 LAST $SEC 1
J 0
(2300 1725);
DISPLAY 0.936170 (2300 1725);
PAINT MONO (2300 1725);
DISPLAY INVISIBLE (2300 1725);
FORCEADD PVCCIO_CPU1..1
(2250 1700);
FORCEPROP 3 LASTPIN (2250 1650) SIG_NAME PVCCIO_CPU1\g
J 0
(2260 1660);
DISPLAY 0.659574 (2260 1660);
PAINT MONO (2260 1660);
DISPLAY INVISIBLE (2260 1660);
FORCEPROP 1 LAST HDL_POWER PVCCIO_CPU1
J 1
(2250 1750);
DISPLAY 0.872340 (2250 1750);
PAINT GREEN (2250 1750);
DISPLAY INVISIBLE (2250 1750);
FORCEPROP 1 LAST BODY_TYPE PLUMBING
J 0
(2205 1657);
DISPLAY 0.340426 (2205 1657);
PAINT GREEN (2205 1657);
DISPLAY INVISIBLE (2205 1657);
FORCEPROP 1 LAST VOLTAGE 1.1V
J 0
(2205 1657);
DISPLAY 0.340426 (2205 1657);
PAINT SKYBLUE (2205 1657);
DISPLAY INVISIBLE (2205 1657);
FORCEPROP 2 LAST CDS_LIB mstr_symbols
J 0
(2250 1700);
PAINT ORANGE (2250 1700);
DISPLAY INVISIBLE (2250 1700);
FORCEPROP 1 LAST PATH I48
J 0
(2300 1725);
DISPLAY 0.872340 (2300 1725);
PAINT AQUA (2300 1725);
DISPLAY INVISIBLE (2300 1725);
FORCEADD GND..1
(2250 1275);
FORCEPROP 3 LASTPIN (2250 1325) SIG_NAME GND\g
J 0
(2260 1335);
DISPLAY 0.659574 (2260 1335);
PAINT MONO (2260 1335);
DISPLAY INVISIBLE (2260 1335);
FORCEPROP 1 LAST HDL_POWER GND
J 0
(2250 1425);
DISPLAY 2.361702 (2250 1425);
PAINT GREEN (2250 1425);
DISPLAY INVISIBLE (2250 1425);
FORCEPROP 1 LAST BODY_TYPE PLUMBING
J 0
(2205 1232);
DISPLAY 0.340426 (2205 1232);
PAINT GREEN (2205 1232);
DISPLAY INVISIBLE (2205 1232);
FORCEPROP 1 LAST VOLTAGE 0
J 0
(2250 1275);
PAINT SKYBLUE (2250 1275);
DISPLAY INVISIBLE (2250 1275);
FORCEPROP 2 LAST BOM_COST SM_CONTROLLER
J 0
(1850 1350);
DISPLAY 1.617021 (1850 1350);
PAINT ORANGE (1850 1350);
DISPLAY INVISIBLE (1850 1350);
FORCEPROP 2 LAST CDS_LIB mstr_symbols
J 0
(2250 1275);
PAINT MONO (2250 1275);
DISPLAY INVISIBLE (2250 1275);
FORCEPROP 1 LAST SIZE 1B
J 0
(2325 1225);
DISPLAY 2.361702 (2325 1225);
PAINT GREEN (2325 1225);
DISPLAY INVISIBLE (2325 1225);
FORCEPROP 1 LAST PATH I49
J 0
(2325 1275);
DISPLAY 0.872340 (2325 1275);
PAINT AQUA (2325 1275);
DISPLAY INVISIBLE (2325 1275);
FORCEPROP 2 LAST ROOM SMB
J 0
(2150 1350);
PAINT MONO (2150 1350);
DISPLAY INVISIBLE (2150 1350);
FORCEADD OFFPAGE..3
(2600 4300);
FORCEPROP 2 LAST $XR0 43 
J 0
(2814 4300);
DISPLAY 0.638298 (2814 4300);
PAINT MONO (2814 4300);
FORCEPROP 2 LAST $XR1 44 
J 0
(2904 4300);
DISPLAY 0.638298 (2904 4300);
PAINT MONO (2904 4300);
FORCEPROP 2 LAST $XR2 45 
J 0
(2994 4300);
DISPLAY 0.638298 (2994 4300);
PAINT MONO (2994 4300);
FORCEPROP 2 LAST $XR3 46 
J 0
(3084 4300);
DISPLAY 0.638298 (3084 4300);
PAINT MONO (3084 4300);
FORCEPROP 2 LAST $XR4 47 
J 0
(3174 4300);
DISPLAY 0.638298 (3174 4300);
PAINT MONO (3174 4300);
FORCEPROP 2 LAST $XR5 48 
J 0
(3264 4300);
DISPLAY 0.638298 (3264 4300);
PAINT MONO (3264 4300);
FORCEPROP 1 LAST COMMENT_BODY TRUE
J 0
(2550 4200);
DISPLAY 1.872340 (2550 4200);
PAINT GREEN (2550 4200);
DISPLAY INVISIBLE (2550 4200);
FORCEPROP 1 LAST OFFPAGE TRUE
J 0
(2925 4175);
PAINT GREEN (2925 4175);
DISPLAY INVISIBLE (2925 4175);
FORCEPROP 2 LAST BOM_COST SM_CONTROLLER
J 0
(3375 4350);
PAINT MONO (3375 4350);
DISPLAY INVISIBLE (3375 4350);
FORCEPROP 2 LAST CDS_LIB mstr_standard
J 0
(2600 4300);
PAINT MONO (2600 4300);
DISPLAY INVISIBLE (2600 4300);
FORCEPROP 2 LAST ROOM SMB
J 0
(3375 4350);
PAINT MONO (3375 4350);
DISPLAY INVISIBLE (3375 4350);
FORCEPROP 2 LAST PATH I5
J 0
(2925 4350);
DISPLAY 1.021277 (2925 4350);
PAINT ORANGE (2925 4350);
DISPLAY INVISIBLE (2925 4350);
FORCEADD OFFPAGE..2
(2625 950);
FORCEPROP 2 LAST $XR0 83 
J 0
(2814 950);
DISPLAY 0.638298 (2814 950);
PAINT MONO (2814 950);
FORCEPROP 2 LAST $XR1 84 
J 0
(2904 950);
DISPLAY 0.638298 (2904 950);
PAINT MONO (2904 950);
FORCEPROP 2 LAST $XR2 85 
J 0
(2994 950);
DISPLAY 0.638298 (2994 950);
PAINT MONO (2994 950);
FORCEPROP 2 LAST $XR3 86 
J 0
(3084 950);
DISPLAY 0.638298 (3084 950);
PAINT MONO (3084 950);
FORCEPROP 2 LAST $XR4 87 
J 0
(3174 950);
DISPLAY 0.638298 (3174 950);
PAINT MONO (3174 950);
FORCEPROP 2 LAST $XR5 88 
J 0
(3264 950);
DISPLAY 0.638298 (3264 950);
PAINT MONO (3264 950);
FORCEPROP 1 LAST COMMENT_BODY TRUE
J 0
(2580 855);
DISPLAY 0.872340 (2580 855);
PAINT GREEN (2580 855);
DISPLAY INVISIBLE (2580 855);
FORCEPROP 1 LAST OFFPAGE TRUE
J 0
(2950 825);
PAINT GREEN (2950 825);
DISPLAY INVISIBLE (2950 825);
FORCEPROP 2 LAST CDS_LIB mstr_standard
J 0
(2625 950);
PAINT ORANGE (2625 950);
DISPLAY INVISIBLE (2625 950);
FORCEPROP 2 LAST BOM_COST SM_CONTROLLER
J 0
(2950 1000);
PAINT MONO (2950 1000);
DISPLAY INVISIBLE (2950 1000);
FORCEPROP 2 LAST PATH I50
J 0
(2925 1000);
DISPLAY 1.021277 (2925 1000);
PAINT ORANGE (2925 1000);
DISPLAY INVISIBLE (2925 1000);
FORCEADD OFFPAGE..3
(2625 900);
FORCEPROP 2 LAST $XR0 83 
J 0
(2839 900);
DISPLAY 0.638298 (2839 900);
PAINT MONO (2839 900);
FORCEPROP 2 LAST $XR1 84 
J 0
(2929 900);
DISPLAY 0.638298 (2929 900);
PAINT MONO (2929 900);
FORCEPROP 2 LAST $XR2 85 
J 0
(3019 900);
DISPLAY 0.638298 (3019 900);
PAINT MONO (3019 900);
FORCEPROP 2 LAST $XR3 86 
J 0
(3109 900);
DISPLAY 0.638298 (3109 900);
PAINT MONO (3109 900);
FORCEPROP 2 LAST $XR4 87 
J 0
(3199 900);
DISPLAY 0.638298 (3199 900);
PAINT MONO (3199 900);
FORCEPROP 2 LAST $XR5 88 
J 0
(3289 900);
DISPLAY 0.638298 (3289 900);
PAINT MONO (3289 900);
FORCEPROP 1 LAST COMMENT_BODY TRUE
J 0
(2575 800);
DISPLAY 1.872340 (2575 800);
PAINT GREEN (2575 800);
DISPLAY INVISIBLE (2575 800);
FORCEPROP 1 LAST OFFPAGE TRUE
J 0
(2950 775);
PAINT GREEN (2950 775);
DISPLAY INVISIBLE (2950 775);
FORCEPROP 2 LAST CDS_LIB mstr_standard
J 0
(2625 900);
PAINT MONO (2625 900);
DISPLAY INVISIBLE (2625 900);
FORCEPROP 2 LAST BOM_COST SM_CONTROLLER
J 0
(3300 950);
PAINT MONO (3300 950);
DISPLAY INVISIBLE (3300 950);
FORCEPROP 2 LAST ROOM SMB
J 0
(3300 950);
PAINT MONO (3300 950);
DISPLAY INVISIBLE (3300 950);
FORCEPROP 2 LAST PATH I51
J 0
(2950 950);
DISPLAY 1.021277 (2950 950);
PAINT ORANGE (2950 950);
DISPLAY INVISIBLE (2950 950);
FORCEADD PVPP_KLM..1
(1675 1700);
FORCEPROP 3 LASTPIN (1675 1650) SIG_NAME PVPP_KLM\g
J 0
(1685 1660);
DISPLAY 0.659574 (1685 1660);
PAINT MONO (1685 1660);
DISPLAY INVISIBLE (1685 1660);
FORCEPROP 1 LAST HDL_POWER PVPP_KLM
J 1
(1675 1750);
DISPLAY 0.872340 (1675 1750);
PAINT GREEN (1675 1750);
DISPLAY INVISIBLE (1675 1750);
FORCEPROP 1 LAST BODY_TYPE PLUMBING
J 0
(1630 1657);
DISPLAY 0.340426 (1630 1657);
PAINT GREEN (1630 1657);
DISPLAY INVISIBLE (1630 1657);
FORCEPROP 1 LAST VOLTAGE 2.5V
J 0
(1630 1657);
DISPLAY 0.340426 (1630 1657);
PAINT SKYBLUE (1630 1657);
DISPLAY INVISIBLE (1630 1657);
FORCEPROP 2 LAST BOM_COST SM_CONTROLLER
J 0
(1675 1800);
DISPLAY 1.617021 (1675 1800);
PAINT ORANGE (1675 1800);
DISPLAY INVISIBLE (1675 1800);
FORCEPROP 2 LAST CDS_LIB mstr_symbols
J 0
(1675 1700);
PAINT ORANGE (1675 1700);
DISPLAY INVISIBLE (1675 1700);
FORCEPROP 1 LAST PATH I52
J 0
(1725 1725);
DISPLAY 0.872340 (1725 1725);
PAINT AQUA (1725 1725);
DISPLAY INVISIBLE (1725 1725);
FORCEPROP 2 LAST ROOM SMB
J 0
(1675 1775);
PAINT MONO (1675 1775);
DISPLAY INVISIBLE (1675 1775);
FORCEADD CAP_A..1
(1675 1500);
FORCEPROP 1 LAST LOCATION C3B5
J 0
(1725 1600);
DISPLAY 0.617021 (1725 1600);
PAINT AQUA (1725 1600);
FORCEPROP 1 LAST PART_NUMBER A36096-030
J 0
(1725 1350);
DISPLAY 0.617021 (1725 1350);
PAINT BLUE (1725 1350);
FORCEPROP 1 LAST VALUE 0.1UF
J 0
(1725 1550);
DISPLAY 0.617021 (1725 1550);
PAINT SKYBLUE (1725 1550);
FORCEPROP 1 LAST TOLERANCE 10%
J 0
(1725 1450);
DISPLAY 0.617021 (1725 1450);
PAINT SKYBLUE (1725 1450);
FORCEPROP 1 LAST PACK_TYPE 0402V
J 0
(1725 1300);
DISPLAY 0.617021 (1725 1300);
PAINT SKYBLUE (1725 1300);
FORCEPROP 1 LAST VOLTAGE 16V
J 0
(1725 1500);
DISPLAY 0.617021 (1725 1500);
PAINT SKYBLUE (1725 1500);
FORCEPROP 1 LAST MATERIAL X7R
J 0
(1725 1400);
DISPLAY 0.617021 (1725 1400);
PAINT SKYBLUE (1725 1400);
FORCEPROP 1 LASTPIN (1675 1600) $PN 1
J 0
(1685 1580);
DISPLAY 0.617021 (1685 1580);
PAINT MONO (1685 1580);
FORCEPROP 1 LASTPIN (1675 1400) $PN 2
J 0
(1685 1380);
DISPLAY 0.617021 (1685 1380);
PAINT MONO (1685 1380);
FORCEPROP 1 LAST PATH I53
J 0
(1725 1650);
DISPLAY 0.978723 (1725 1650);
PAINT WHITE (1725 1650);
DISPLAY INVISIBLE (1725 1650);
FORCEPROP 2 LAST ROOM MEM
J 0
(1725 1625);
PAINT MONO (1725 1625);
DISPLAY INVISIBLE (1725 1625);
FORCEPROP 2 LAST CDS_LOCATION C3B5
J 0
(1725 1600);
DISPLAY 0.617021 (1725 1600);
PAINT AQUA (1725 1600);
DISPLAY INVISIBLE (1725 1600);
FORCEPROP 2 LAST BOM_COST SM_CONTROLLER
J 0
(1725 1650);
DISPLAY 2.170213 (1725 1650);
PAINT ORANGE (1725 1650);
DISPLAY INVISIBLE (1725 1650);
FORCEPROP 2 LAST CD_SEC 1
J 0
(1725 1725);
DISPLAY 1.617021 (1725 1725);
PAINT MONO (1725 1725);
DISPLAY INVISIBLE (1725 1725);
FORCEPROP 2 LAST SIGNAL_MODEL DEFAULT_CAPACITOR_100000pF_2_1
J 0
(1725 1725);
DISPLAY 1.617021 (1725 1725);
PAINT MONO (1725 1725);
DISPLAY INVISIBLE (1725 1725);
FORCEPROP 2 LAST CDS_LIB dev_discrete
J 0
(1675 1500);
PAINT ORANGE (1675 1500);
DISPLAY INVISIBLE (1675 1500);
FORCEPROP 2 LAST CDS_SEC 1
J 0
(1725 1700);
DISPLAY 1.404255 (1725 1700);
PAINT ORANGE (1725 1700);
DISPLAY INVISIBLE (1725 1700);
FORCEPROP 2 LAST $SEC 1
J 0
(1725 1700);
DISPLAY 0.936170 (1725 1700);
PAINT MONO (1725 1700);
DISPLAY INVISIBLE (1725 1700);
FORCEADD GND..1
(1675 1250);
FORCEPROP 3 LASTPIN (1675 1300) SIG_NAME GND\g
J 0
(1685 1310);
DISPLAY 0.659574 (1685 1310);
PAINT MONO (1685 1310);
DISPLAY INVISIBLE (1685 1310);
FORCEPROP 1 LAST HDL_POWER GND
J 0
(1675 1400);
DISPLAY 2.361702 (1675 1400);
PAINT GREEN (1675 1400);
DISPLAY INVISIBLE (1675 1400);
FORCEPROP 1 LAST BODY_TYPE PLUMBING
J 0
(1630 1207);
DISPLAY 0.340426 (1630 1207);
PAINT GREEN (1630 1207);
DISPLAY INVISIBLE (1630 1207);
FORCEPROP 1 LAST VOLTAGE 0
J 0
(1675 1250);
PAINT SKYBLUE (1675 1250);
DISPLAY INVISIBLE (1675 1250);
FORCEPROP 2 LAST CDS_LIB mstr_symbols
J 0
(1675 1250);
PAINT MONO (1675 1250);
DISPLAY INVISIBLE (1675 1250);
FORCEPROP 1 LAST SIZE 1B
J 0
(1750 1200);
DISPLAY 2.361702 (1750 1200);
PAINT GREEN (1750 1200);
DISPLAY INVISIBLE (1750 1200);
FORCEPROP 2 LAST BOM_COST SM_CONTROLLER
J 0
(1275 1325);
DISPLAY 1.617021 (1275 1325);
PAINT ORANGE (1275 1325);
DISPLAY INVISIBLE (1275 1325);
FORCEPROP 1 LAST PATH I54
J 0
(1750 1250);
DISPLAY 0.872340 (1750 1250);
PAINT AQUA (1750 1250);
DISPLAY INVISIBLE (1750 1250);
FORCEPROP 2 LAST ROOM SMB
J 0
(1575 1325);
PAINT MONO (1575 1325);
DISPLAY INVISIBLE (1575 1325);
FORCEADD RES..1
(1600 900);
FORCEPROP 1 LAST LOCATION R7M5
J 0
(1300 850);
DISPLAY 0.617021 (1300 850);
PAINT AQUA (1300 850);
FORCEPROP 1 LAST PART_NUMBER G21796-173
J 0
(1825 750);
DISPLAY 0.617021 (1825 750);
PAINT BLUE (1825 750);
FORCEPROP 1 LAST VALUE 20.0
J 2
(1550 850);
DISPLAY 0.617021 (1550 850);
PAINT SKYBLUE (1550 850);
FORCEPROP 1 LAST TOLERANCE 1%
J 0
(1875 850);
DISPLAY 0.617021 (1875 850);
PAINT SKYBLUE (1875 850);
FORCEPROP 1 LAST PACK_TYPE 0402
J 0
(1650 850);
DISPLAY 0.617021 (1650 850);
PAINT SKYBLUE (1650 850);
FORCEPROP 1 LAST MATERIAL CHIP
J 0
(2000 800);
DISPLAY 0.617021 (2000 800);
PAINT SKYBLUE (2000 800);
FORCEPROP 1 LAST WATTAGE 1/16W
J 2
(1950 800);
DISPLAY 0.617021 (1950 800);
PAINT SKYBLUE (1950 800);
FORCEPROP 1 LASTPIN (1700 900) $PN 2
J 0
(1662 912);
DISPLAY 0.617021 (1662 912);
PAINT MONO (1662 912);
FORCEPROP 1 LASTPIN (1500 900) $PN 1
J 0
(1512 912);
DISPLAY 0.617021 (1512 912);
PAINT MONO (1512 912);
FORCEPROP 2 LAST CDS_LIB mstr_discrete
J 0
(1600 900);
PAINT ORANGE (1600 900);
DISPLAY INVISIBLE (1600 900);
FORCEPROP 2 LAST CDS_SEC 1
J 0
(1550 1100);
DISPLAY 1.404255 (1550 1100);
PAINT ORANGE (1550 1100);
DISPLAY INVISIBLE (1550 1100);
FORCEPROP 2 LAST $SEC 1
J 0
(1550 1100);
DISPLAY 0.936170 (1550 1100);
PAINT MONO (1550 1100);
DISPLAY INVISIBLE (1550 1100);
FORCEPROP 2 LAST CDS_LOCATION R7M5
J 0
(1300 850);
DISPLAY 0.617021 (1300 850);
PAINT AQUA (1300 850);
DISPLAY INVISIBLE (1300 850);
FORCEPROP 1 LAST PATH I55
J 0
(1550 1050);
DISPLAY 0.978723 (1550 1050);
PAINT WHITE (1550 1050);
DISPLAY INVISIBLE (1550 1050);
FORCEPROP 2 LAST ROOM MEM
J 0
(1800 900);
DISPLAY 1.404255 (1800 900);
PAINT ORANGE (1800 900);
DISPLAY INVISIBLE (1800 900);
FORCEADD RES..1
(1600 950);
FORCEPROP 1 LAST LOCATION R7M4
J 0
(1550 1025);
DISPLAY 0.617021 (1550 1025);
PAINT AQUA (1550 1025);
FORCEPROP 1 LAST PART_NUMBER G21796-173
J 0
(1800 1100);
DISPLAY 0.617021 (1800 1100);
PAINT BLUE (1800 1100);
FORCEPROP 1 LAST VALUE 20.0
J 2
(1550 1000);
DISPLAY 0.617021 (1550 1000);
PAINT SKYBLUE (1550 1000);
FORCEPROP 1 LAST TOLERANCE 1%
J 0
(1850 1000);
DISPLAY 0.617021 (1850 1000);
PAINT SKYBLUE (1850 1000);
FORCEPROP 1 LAST PACK_TYPE 0402
J 0
(1650 1000);
DISPLAY 0.617021 (1650 1000);
PAINT SKYBLUE (1650 1000);
FORCEPROP 1 LAST MATERIAL CHIP
J 0
(2000 1050);
DISPLAY 0.617021 (2000 1050);
PAINT SKYBLUE (2000 1050);
FORCEPROP 1 LAST WATTAGE 1/16W
J 2
(1950 1050);
DISPLAY 0.617021 (1950 1050);
PAINT SKYBLUE (1950 1050);
FORCEPROP 1 LASTPIN (1700 950) $PN 2
J 0
(1662 962);
DISPLAY 0.617021 (1662 962);
PAINT MONO (1662 962);
FORCEPROP 1 LASTPIN (1500 950) $PN 1
J 0
(1512 962);
DISPLAY 0.617021 (1512 962);
PAINT MONO (1512 962);
FORCEPROP 2 LAST CDS_LIB mstr_discrete
J 0
(1600 950);
PAINT ORANGE (1600 950);
DISPLAY INVISIBLE (1600 950);
FORCEPROP 2 LAST CDS_SEC 1
J 0
(1550 1150);
DISPLAY 1.404255 (1550 1150);
PAINT ORANGE (1550 1150);
DISPLAY INVISIBLE (1550 1150);
FORCEPROP 2 LAST $SEC 1
J 0
(1550 1150);
DISPLAY 0.936170 (1550 1150);
PAINT MONO (1550 1150);
DISPLAY INVISIBLE (1550 1150);
FORCEPROP 2 LAST CDS_LOCATION R7M4
J 0
(1550 1025);
DISPLAY 0.617021 (1550 1025);
PAINT AQUA (1550 1025);
DISPLAY INVISIBLE (1550 1025);
FORCEPROP 1 LAST PATH I56
J 0
(1550 1100);
DISPLAY 0.978723 (1550 1100);
PAINT WHITE (1550 1100);
DISPLAY INVISIBLE (1550 1100);
FORCEPROP 2 LAST ROOM MEM
J 0
(1800 1050);
DISPLAY 1.404255 (1800 1050);
PAINT ORANGE (1800 1050);
DISPLAY INVISIBLE (1800 1050);
FORCEADD PVPP_DEF..1
(625 3575);
FORCEPROP 3 LASTPIN (625 3525) SIG_NAME PVPP_DEF\g
J 0
(635 3535);
DISPLAY 0.659574 (635 3535);
PAINT MONO (635 3535);
DISPLAY INVISIBLE (635 3535);
FORCEPROP 1 LAST HDL_POWER PVPP_DEF
J 1
(625 3625);
DISPLAY 0.872340 (625 3625);
PAINT GREEN (625 3625);
DISPLAY INVISIBLE (625 3625);
FORCEPROP 1 LAST BODY_TYPE PLUMBING
J 0
(580 3532);
DISPLAY 0.340426 (580 3532);
PAINT GREEN (580 3532);
DISPLAY INVISIBLE (580 3532);
FORCEPROP 1 LAST VOLTAGE 2.5V
J 0
(580 3532);
DISPLAY 0.340426 (580 3532);
PAINT SKYBLUE (580 3532);
DISPLAY INVISIBLE (580 3532);
FORCEPROP 2 LAST BOM_COST SM_CONTROLLER
J 0
(625 3675);
DISPLAY 1.617021 (625 3675);
PAINT ORANGE (625 3675);
DISPLAY INVISIBLE (625 3675);
FORCEPROP 2 LAST CDS_LIB mstr_symbols
J 0
(625 3575);
PAINT ORANGE (625 3575);
DISPLAY INVISIBLE (625 3575);
FORCEPROP 1 LAST PATH I60
J 0
(675 3600);
DISPLAY 0.872340 (675 3600);
PAINT AQUA (675 3600);
DISPLAY INVISIBLE (675 3600);
FORCEPROP 2 LAST ROOM SMB
J 0
(625 3650);
PAINT MONO (625 3650);
DISPLAY INVISIBLE (625 3650);
FORCEADD PCA9617..1
(150 3250);
FORCEPROP 1 LAST POWER_GROUP GND=GND
J 0
(-200 3000);
DISPLAY 0.617021 (-200 3000);
PAINT ORANGE (-200 3000);
FORCEPROP 1 LAST LOCATION U7E1
J 0
(-200 3575);
DISPLAY 0.617021 (-200 3575);
PAINT AQUA (-200 3575);
FORCEPROP 1 LAST PART_NUMBER G81764-001
J 0
(-200 3050);
DISPLAY 0.617021 (-200 3050);
PAINT BLUE (-200 3050);
FORCEPROP 1 LAST MATERIAL IC
J 0
(-200 3525);
DISPLAY 0.617021 (-200 3525);
PAINT SKYBLUE (-200 3525);
FORCEPROP 2 LASTPIN (550 3400) $PN 8
J 0
(560 3410);
DISPLAY 0.617021 (560 3410);
PAINT MONO (560 3410);
FORCEPROP 2 LASTPIN (-250 3400) $PN 1
J 2
(-260 3410);
DISPLAY 0.617021 (-260 3410);
PAINT MONO (-260 3410);
FORCEPROP 2 LASTPIN (550 3250) $PN 6
J 0
(560 3260);
DISPLAY 0.617021 (560 3260);
PAINT MONO (560 3260);
FORCEPROP 2 LASTPIN (-250 3250) $PN 3
J 2
(-260 3260);
DISPLAY 0.617021 (-260 3260);
PAINT MONO (-260 3260);
FORCEPROP 2 LASTPIN (550 3300) $PN 7
J 0
(560 3310);
DISPLAY 0.617021 (560 3310);
PAINT MONO (560 3310);
FORCEPROP 2 LASTPIN (-250 3300) $PN 2
J 2
(-260 3310);
DISPLAY 0.617021 (-260 3310);
PAINT MONO (-260 3310);
FORCEPROP 2 LASTPIN (-250 3150) $PN 5
J 2
(-260 3160);
DISPLAY 0.617021 (-260 3160);
PAINT MONO (-260 3160);
FORCEPROP 1 LAST PACK_TYPE SSOP
J 0
(-200 3625);
PAINT SKYBLUE (-200 3625);
DISPLAY INVISIBLE (-200 3625);
FORCEPROP 2 LAST CDS_LIB mstr_digital
J 0
(150 3250);
PAINT MONO (150 3250);
DISPLAY INVISIBLE (150 3250);
FORCEPROP 2 LAST BOM_COST SM_CONTROLLER
J 0
(-200 3625);
PAINT MONO (-200 3625);
DISPLAY INVISIBLE (-200 3625);
FORCEPROP 2 LAST CDS_SEC 1
J 0
(-200 3625);
DISPLAY 1.404255 (-200 3625);
PAINT ORANGE (-200 3625);
DISPLAY INVISIBLE (-200 3625);
FORCEPROP 2 LAST $SEC 1
J 0
(-200 3625);
DISPLAY 0.936170 (-200 3625);
PAINT MONO (-200 3625);
DISPLAY INVISIBLE (-200 3625);
FORCEPROP 2 LAST CDS_LOCATION U7E1
J 0
(-200 3575);
DISPLAY 0.617021 (-200 3575);
PAINT AQUA (-200 3575);
DISPLAY INVISIBLE (-200 3575);
FORCEPROP 1 LAST PATH I61
J 0
(275 3525);
PAINT GREEN (275 3525);
DISPLAY INVISIBLE (275 3525);
FORCEPROP 2 LAST ROOM MEM
J 0
(-200 3625);
PAINT MONO (-200 3625);
DISPLAY INVISIBLE (-200 3625);
FORCEADD PVPP_GHJ..1
(600 2425);
FORCEPROP 3 LASTPIN (600 2375) SIG_NAME PVPP_GHJ\g
J 0
(610 2385);
DISPLAY 0.659574 (610 2385);
PAINT MONO (610 2385);
DISPLAY INVISIBLE (610 2385);
FORCEPROP 1 LAST HDL_POWER PVPP_GHJ
J 1
(600 2475);
DISPLAY 0.872340 (600 2475);
PAINT GREEN (600 2475);
DISPLAY INVISIBLE (600 2475);
FORCEPROP 1 LAST BODY_TYPE PLUMBING
J 0
(555 2382);
DISPLAY 0.340426 (555 2382);
PAINT GREEN (555 2382);
DISPLAY INVISIBLE (555 2382);
FORCEPROP 1 LAST VOLTAGE 2.5V
J 0
(555 2382);
DISPLAY 0.340426 (555 2382);
PAINT SKYBLUE (555 2382);
DISPLAY INVISIBLE (555 2382);
FORCEPROP 2 LAST BOM_COST SM_CONTROLLER
J 0
(600 2525);
DISPLAY 1.617021 (600 2525);
PAINT ORANGE (600 2525);
DISPLAY INVISIBLE (600 2525);
FORCEPROP 2 LAST CDS_LIB mstr_symbols
J 0
(600 2425);
PAINT ORANGE (600 2425);
DISPLAY INVISIBLE (600 2425);
FORCEPROP 1 LAST PATH I62
J 0
(650 2450);
DISPLAY 0.872340 (650 2450);
PAINT AQUA (650 2450);
DISPLAY INVISIBLE (650 2450);
FORCEPROP 2 LAST ROOM SMB
J 0
(600 2500);
PAINT MONO (600 2500);
DISPLAY INVISIBLE (600 2500);
FORCEADD PCA9617..1
(150 2100);
FORCEPROP 1 LAST POWER_GROUP GND=GND
J 0
(-200 1850);
DISPLAY 0.617021 (-200 1850);
PAINT ORANGE (-200 1850);
FORCEPROP 1 LAST LOCATION U4G1
J 0
(-200 2425);
DISPLAY 0.617021 (-200 2425);
PAINT AQUA (-200 2425);
FORCEPROP 1 LAST PART_NUMBER G81764-001
J 0
(-200 1900);
DISPLAY 0.617021 (-200 1900);
PAINT BLUE (-200 1900);
FORCEPROP 1 LAST MATERIAL IC
J 0
(-200 2375);
DISPLAY 0.617021 (-200 2375);
PAINT SKYBLUE (-200 2375);
FORCEPROP 2 LASTPIN (550 2250) $PN 8
J 0
(560 2260);
DISPLAY 0.617021 (560 2260);
PAINT MONO (560 2260);
FORCEPROP 2 LASTPIN (-250 2250) $PN 1
J 2
(-260 2260);
DISPLAY 0.617021 (-260 2260);
PAINT MONO (-260 2260);
FORCEPROP 2 LASTPIN (550 2100) $PN 6
J 0
(560 2110);
DISPLAY 0.617021 (560 2110);
PAINT MONO (560 2110);
FORCEPROP 2 LASTPIN (-250 2100) $PN 3
J 2
(-260 2110);
DISPLAY 0.617021 (-260 2110);
PAINT MONO (-260 2110);
FORCEPROP 2 LASTPIN (550 2150) $PN 7
J 0
(560 2160);
DISPLAY 0.617021 (560 2160);
PAINT MONO (560 2160);
FORCEPROP 2 LASTPIN (-250 2150) $PN 2
J 2
(-260 2160);
DISPLAY 0.617021 (-260 2160);
PAINT MONO (-260 2160);
FORCEPROP 2 LASTPIN (-250 2000) $PN 5
J 2
(-260 2010);
DISPLAY 0.617021 (-260 2010);
PAINT MONO (-260 2010);
FORCEPROP 1 LAST PACK_TYPE SSOP
J 0
(-200 2475);
PAINT SKYBLUE (-200 2475);
DISPLAY INVISIBLE (-200 2475);
FORCEPROP 2 LAST CDS_LIB mstr_digital
J 0
(150 2100);
PAINT MONO (150 2100);
DISPLAY INVISIBLE (150 2100);
FORCEPROP 2 LAST BOM_COST SM_CONTROLLER
J 0
(-200 2475);
PAINT MONO (-200 2475);
DISPLAY INVISIBLE (-200 2475);
FORCEPROP 2 LAST CDS_SEC 1
J 0
(-200 2475);
DISPLAY 1.404255 (-200 2475);
PAINT ORANGE (-200 2475);
DISPLAY INVISIBLE (-200 2475);
FORCEPROP 2 LAST $SEC 1
J 0
(-200 2475);
DISPLAY 0.936170 (-200 2475);
PAINT MONO (-200 2475);
DISPLAY INVISIBLE (-200 2475);
FORCEPROP 2 LAST CDS_LOCATION U4G1
J 0
(-200 2425);
DISPLAY 0.617021 (-200 2425);
PAINT AQUA (-200 2425);
DISPLAY INVISIBLE (-200 2425);
FORCEPROP 1 LAST PATH I63
J 0
(275 2375);
PAINT GREEN (275 2375);
DISPLAY INVISIBLE (275 2375);
FORCEPROP 2 LAST ROOM MEM
J 0
(-200 2475);
PAINT MONO (-200 2475);
DISPLAY INVISIBLE (-200 2475);
FORCEADD PVCCIO_CPU0..1
(-500 3825);
FORCEPROP 3 LASTPIN (-500 3775) SIG_NAME PVCCIO_CPU0\g
J 0
(-490 3785);
DISPLAY 0.659574 (-490 3785);
PAINT MONO (-490 3785);
DISPLAY INVISIBLE (-490 3785);
FORCEPROP 1 LAST HDL_POWER PVCCIO_CPU0
J 1
(-500 3875);
DISPLAY 0.872340 (-500 3875);
PAINT GREEN (-500 3875);
DISPLAY INVISIBLE (-500 3875);
FORCEPROP 1 LAST BODY_TYPE PLUMBING
J 0
(-545 3782);
DISPLAY 0.340426 (-545 3782);
PAINT GREEN (-545 3782);
DISPLAY INVISIBLE (-545 3782);
FORCEPROP 1 LAST VOLTAGE 1.1V
J 0
(-545 3782);
DISPLAY 0.340426 (-545 3782);
PAINT SKYBLUE (-545 3782);
DISPLAY INVISIBLE (-545 3782);
FORCEPROP 2 LAST CDS_LIB mstr_symbols
J 0
(-500 3825);
PAINT ORANGE (-500 3825);
DISPLAY INVISIBLE (-500 3825);
FORCEPROP 1 LAST PATH I64
J 0
(-450 3850);
DISPLAY 0.872340 (-450 3850);
PAINT AQUA (-450 3850);
DISPLAY INVISIBLE (-450 3850);
FORCEADD RES..2
R 2
(-675 3600);
FORCEPROP 1 LAST LOCATION R3R13
J 2
(-720 3725);
DISPLAY 0.617021 (-720 3725);
PAINT AQUA (-720 3725);
FORCEPROP 1 LAST PART_NUMBER G21796-294
J 2
(-715 3475);
DISPLAY 0.617021 (-715 3475);
PAINT BLUE (-715 3475);
FORCEPROP 1 LAST VALUE 240
J 2
(-720 3675);
DISPLAY 0.617021 (-720 3675);
PAINT SKYBLUE (-720 3675);
FORCEPROP 1 LAST TOLERANCE 1.0%
J 2
(-720 3625);
DISPLAY 0.617021 (-720 3625);
PAINT SKYBLUE (-720 3625);
FORCEPROP 1 LAST PACK_TYPE 0402
J 2
(-715 3425);
DISPLAY 0.617021 (-715 3425);
PAINT SKYBLUE (-715 3425);
FORCEPROP 1 LAST MATERIAL CHIP
J 2
(-715 3525);
DISPLAY 0.617021 (-715 3525);
PAINT SKYBLUE (-715 3525);
FORCEPROP 1 LAST WATTAGE 1/16W
J 2
(-715 3575);
DISPLAY 0.617021 (-715 3575);
PAINT SKYBLUE (-715 3575);
FORCEPROP 1 LASTPIN (-675 3500) $PN 2
J 2
(-680 3510);
DISPLAY 0.617021 (-680 3510);
PAINT MONO (-680 3510);
FORCEPROP 1 LASTPIN (-675 3700) $PN 1
J 2
(-680 3662);
DISPLAY 0.617021 (-680 3662);
PAINT MONO (-680 3662);
FORCEPROP 2 LAST CDS_LIB mstr_discrete
J 0
(-675 3600);
PAINT MONO (-675 3600);
DISPLAY INVISIBLE (-675 3600);
FORCEPROP 2 LAST SIGNAL_MODEL DEFAULT_RESISTOR_750OHM_2_1
J 0
(-725 3850);
DISPLAY 1.617021 (-725 3850);
PAINT MONO (-725 3850);
DISPLAY INVISIBLE (-725 3850);
FORCEPROP 2 LAST CD_SEC 1
J 0
(-725 3850);
DISPLAY 1.617021 (-725 3850);
PAINT MONO (-725 3850);
DISPLAY INVISIBLE (-725 3850);
FORCEPROP 2 LAST BOM_COST SM_CONTROLLER
J 2
(-1250 3700);
DISPLAY 1.617021 (-1250 3700);
PAINT PEACH (-1250 3700);
DISPLAY INVISIBLE (-1250 3700);
FORCEPROP 2 LAST CDS_SEC 1
J 0
(-725 3825);
DISPLAY 1.404255 (-725 3825);
PAINT ORANGE (-725 3825);
DISPLAY INVISIBLE (-725 3825);
FORCEPROP 2 LAST $SEC 1
J 0
(-725 3825);
DISPLAY 0.936170 (-725 3825);
PAINT MONO (-725 3825);
DISPLAY INVISIBLE (-725 3825);
FORCEPROP 2 LAST CDS_LOCATION R3R13
J 2
(-720 3725);
DISPLAY 0.617021 (-720 3725);
PAINT AQUA (-720 3725);
DISPLAY INVISIBLE (-720 3725);
FORCEPROP 1 LAST PATH I65
J 2
(-725 3775);
DISPLAY 0.978723 (-725 3775);
PAINT WHITE (-725 3775);
DISPLAY INVISIBLE (-725 3775);
FORCEPROP 2 LAST ROOM MEM
J 0
(-700 3750);
PAINT MONO (-700 3750);
DISPLAY INVISIBLE (-700 3750);
FORCEADD PVCCIO_CPU0..1
(-925 3925);
FORCEPROP 3 LASTPIN (-925 3875) SIG_NAME PVCCIO_CPU0\g
J 0
(-915 3885);
DISPLAY 0.659574 (-915 3885);
PAINT MONO (-915 3885);
DISPLAY INVISIBLE (-915 3885);
FORCEPROP 1 LAST HDL_POWER PVCCIO_CPU0
J 1
(-925 3975);
DISPLAY 0.872340 (-925 3975);
PAINT GREEN (-925 3975);
DISPLAY INVISIBLE (-925 3975);
FORCEPROP 1 LAST BODY_TYPE PLUMBING
J 0
(-970 3882);
DISPLAY 0.340426 (-970 3882);
PAINT GREEN (-970 3882);
DISPLAY INVISIBLE (-970 3882);
FORCEPROP 1 LAST VOLTAGE 1.1V
J 0
(-970 3882);
DISPLAY 0.340426 (-970 3882);
PAINT SKYBLUE (-970 3882);
DISPLAY INVISIBLE (-970 3882);
FORCEPROP 2 LAST CDS_LIB mstr_symbols
J 0
(-925 3925);
PAINT ORANGE (-925 3925);
DISPLAY INVISIBLE (-925 3925);
FORCEPROP 1 LAST PATH I66
J 0
(-875 3950);
DISPLAY 0.872340 (-875 3950);
PAINT AQUA (-875 3950);
DISPLAY INVISIBLE (-875 3950);
FORCEADD RES..2
R 2
(-1050 3600);
FORCEPROP 1 LAST LOCATION R3P60
J 2
(-1095 3725);
DISPLAY 0.617021 (-1095 3725);
PAINT AQUA (-1095 3725);
FORCEPROP 1 LAST PART_NUMBER G21796-294
J 2
(-1090 3475);
DISPLAY 0.617021 (-1090 3475);
PAINT BLUE (-1090 3475);
FORCEPROP 1 LAST VALUE 240
J 2
(-1095 3675);
DISPLAY 0.617021 (-1095 3675);
PAINT SKYBLUE (-1095 3675);
FORCEPROP 1 LAST TOLERANCE 1.0%
J 2
(-1095 3625);
DISPLAY 0.617021 (-1095 3625);
PAINT SKYBLUE (-1095 3625);
FORCEPROP 1 LAST PACK_TYPE 0402
J 2
(-1090 3425);
DISPLAY 0.617021 (-1090 3425);
PAINT SKYBLUE (-1090 3425);
FORCEPROP 1 LAST MATERIAL CHIP
J 2
(-1090 3525);
DISPLAY 0.617021 (-1090 3525);
PAINT SKYBLUE (-1090 3525);
FORCEPROP 1 LAST WATTAGE 1/16W
J 2
(-1090 3575);
DISPLAY 0.617021 (-1090 3575);
PAINT SKYBLUE (-1090 3575);
FORCEPROP 1 LASTPIN (-1050 3500) $PN 2
J 2
(-1055 3510);
DISPLAY 0.617021 (-1055 3510);
PAINT MONO (-1055 3510);
FORCEPROP 1 LASTPIN (-1050 3700) $PN 1
J 2
(-1055 3662);
DISPLAY 0.617021 (-1055 3662);
PAINT MONO (-1055 3662);
FORCEPROP 2 LAST CD_SEC 1
J 0
(-1100 3850);
DISPLAY 1.617021 (-1100 3850);
PAINT MONO (-1100 3850);
DISPLAY INVISIBLE (-1100 3850);
FORCEPROP 2 LAST SIGNAL_MODEL DEFAULT_RESISTOR_750OHM_2_1
J 0
(-1100 3850);
DISPLAY 1.617021 (-1100 3850);
PAINT MONO (-1100 3850);
DISPLAY INVISIBLE (-1100 3850);
FORCEPROP 2 LAST CDS_LIB mstr_discrete
J 0
(-1050 3600);
PAINT MONO (-1050 3600);
DISPLAY INVISIBLE (-1050 3600);
FORCEPROP 2 LAST BOM_COST SM_CONTROLLER
J 2
(-1625 3700);
DISPLAY 1.617021 (-1625 3700);
PAINT PEACH (-1625 3700);
DISPLAY INVISIBLE (-1625 3700);
FORCEPROP 2 LAST CDS_SEC 1
J 0
(-1100 3825);
DISPLAY 1.404255 (-1100 3825);
PAINT ORANGE (-1100 3825);
DISPLAY INVISIBLE (-1100 3825);
FORCEPROP 2 LAST $SEC 1
J 0
(-1100 3825);
DISPLAY 0.936170 (-1100 3825);
PAINT MONO (-1100 3825);
DISPLAY INVISIBLE (-1100 3825);
FORCEPROP 1 LAST PATH I67
J 2
(-1100 3775);
DISPLAY 0.978723 (-1100 3775);
PAINT WHITE (-1100 3775);
DISPLAY INVISIBLE (-1100 3775);
FORCEPROP 2 LAST ROOM MEM
J 0
(-1075 3750);
PAINT MONO (-1075 3750);
DISPLAY INVISIBLE (-1075 3750);
FORCEADD PVCCIO_CPU1..1
(-525 2675);
FORCEPROP 3 LASTPIN (-525 2625) SIG_NAME PVCCIO_CPU1\g
J 0
(-515 2635);
DISPLAY 0.659574 (-515 2635);
PAINT MONO (-515 2635);
DISPLAY INVISIBLE (-515 2635);
FORCEPROP 1 LAST HDL_POWER PVCCIO_CPU1
J 1
(-525 2725);
DISPLAY 0.872340 (-525 2725);
PAINT GREEN (-525 2725);
DISPLAY INVISIBLE (-525 2725);
FORCEPROP 1 LAST BODY_TYPE PLUMBING
J 0
(-570 2632);
DISPLAY 0.340426 (-570 2632);
PAINT GREEN (-570 2632);
DISPLAY INVISIBLE (-570 2632);
FORCEPROP 1 LAST VOLTAGE 1.1V
J 0
(-570 2632);
DISPLAY 0.340426 (-570 2632);
PAINT SKYBLUE (-570 2632);
DISPLAY INVISIBLE (-570 2632);
FORCEPROP 2 LAST CDS_LIB mstr_symbols
J 0
(-525 2675);
PAINT ORANGE (-525 2675);
DISPLAY INVISIBLE (-525 2675);
FORCEPROP 1 LAST PATH I69
J 0
(-475 2700);
DISPLAY 0.872340 (-475 2700);
PAINT AQUA (-475 2700);
DISPLAY INVISIBLE (-475 2700);
FORCEADD CAP_A..1
(1475 4900);
FORCEPROP 1 LAST LOCATION C6F3
J 0
(1525 5000);
DISPLAY 0.617021 (1525 5000);
PAINT AQUA (1525 5000);
FORCEPROP 1 LAST PART_NUMBER A36096-030
J 0
(1525 4750);
DISPLAY 0.617021 (1525 4750);
PAINT BLUE (1525 4750);
FORCEPROP 1 LAST VALUE 0.1UF
J 0
(1525 4950);
DISPLAY 0.617021 (1525 4950);
PAINT SKYBLUE (1525 4950);
FORCEPROP 1 LAST TOLERANCE 10%
J 0
(1525 4850);
DISPLAY 0.617021 (1525 4850);
PAINT SKYBLUE (1525 4850);
FORCEPROP 1 LAST PACK_TYPE 0402V
J 0
(1525 4700);
DISPLAY 0.617021 (1525 4700);
PAINT SKYBLUE (1525 4700);
FORCEPROP 1 LAST VOLTAGE 16V
J 0
(1525 4900);
DISPLAY 0.617021 (1525 4900);
PAINT SKYBLUE (1525 4900);
FORCEPROP 1 LAST MATERIAL X7R
J 0
(1525 4800);
DISPLAY 0.617021 (1525 4800);
PAINT SKYBLUE (1525 4800);
FORCEPROP 1 LASTPIN (1475 5000) $PN 1
J 0
(1485 4980);
DISPLAY 0.617021 (1485 4980);
PAINT MONO (1485 4980);
FORCEPROP 1 LASTPIN (1475 4800) $PN 2
J 0
(1485 4780);
DISPLAY 0.617021 (1485 4780);
PAINT MONO (1485 4780);
FORCEPROP 1 LAST PATH I7
J 0
(1525 5050);
DISPLAY 0.978723 (1525 5050);
PAINT WHITE (1525 5050);
DISPLAY INVISIBLE (1525 5050);
FORCEPROP 2 LAST ROOM MEM
J 0
(1525 5025);
PAINT MONO (1525 5025);
DISPLAY INVISIBLE (1525 5025);
FORCEPROP 2 LAST CDS_LOCATION C6F3
J 0
(1525 5000);
DISPLAY 0.617021 (1525 5000);
PAINT AQUA (1525 5000);
DISPLAY INVISIBLE (1525 5000);
FORCEPROP 2 LAST BOM_COST SM_CONTROLLER
J 0
(1525 5050);
DISPLAY 2.170213 (1525 5050);
PAINT ORANGE (1525 5050);
DISPLAY INVISIBLE (1525 5050);
FORCEPROP 2 LAST CD_SEC 1
J 0
(1525 5125);
DISPLAY 1.617021 (1525 5125);
PAINT MONO (1525 5125);
DISPLAY INVISIBLE (1525 5125);
FORCEPROP 2 LAST SIGNAL_MODEL DEFAULT_CAPACITOR_100000pF_2_1
J 0
(1525 5125);
DISPLAY 1.617021 (1525 5125);
PAINT MONO (1525 5125);
DISPLAY INVISIBLE (1525 5125);
FORCEPROP 2 LAST CDS_LIB dev_discrete
J 0
(1475 4900);
PAINT ORANGE (1475 4900);
DISPLAY INVISIBLE (1475 4900);
FORCEPROP 2 LAST CDS_SEC 1
J 0
(1525 5100);
DISPLAY 1.404255 (1525 5100);
PAINT ORANGE (1525 5100);
DISPLAY INVISIBLE (1525 5100);
FORCEPROP 2 LAST $SEC 1
J 0
(1525 5100);
DISPLAY 0.936170 (1525 5100);
PAINT MONO (1525 5100);
DISPLAY INVISIBLE (1525 5100);
FORCEADD RES..2
R 2
(-700 2450);
FORCEPROP 1 LAST LOCATION R6T1
J 2
(-745 2575);
DISPLAY 0.617021 (-745 2575);
PAINT AQUA (-745 2575);
FORCEPROP 1 LAST PART_NUMBER G21796-294
J 2
(-740 2325);
DISPLAY 0.617021 (-740 2325);
PAINT BLUE (-740 2325);
FORCEPROP 1 LAST VALUE 240
J 2
(-745 2525);
DISPLAY 0.617021 (-745 2525);
PAINT SKYBLUE (-745 2525);
FORCEPROP 1 LAST TOLERANCE 1.0%
J 2
(-745 2475);
DISPLAY 0.617021 (-745 2475);
PAINT SKYBLUE (-745 2475);
FORCEPROP 1 LAST PACK_TYPE 0402
J 2
(-740 2275);
DISPLAY 0.617021 (-740 2275);
PAINT SKYBLUE (-740 2275);
FORCEPROP 1 LAST MATERIAL CHIP
J 2
(-740 2375);
DISPLAY 0.617021 (-740 2375);
PAINT SKYBLUE (-740 2375);
FORCEPROP 1 LAST WATTAGE 1/16W
J 2
(-740 2425);
DISPLAY 0.617021 (-740 2425);
PAINT SKYBLUE (-740 2425);
FORCEPROP 1 LASTPIN (-700 2350) $PN 2
J 2
(-705 2360);
DISPLAY 0.617021 (-705 2360);
PAINT MONO (-705 2360);
FORCEPROP 1 LASTPIN (-700 2550) $PN 1
J 2
(-705 2512);
DISPLAY 0.617021 (-705 2512);
PAINT MONO (-705 2512);
FORCEPROP 2 LAST CDS_LIB mstr_discrete
J 0
(-700 2450);
PAINT MONO (-700 2450);
DISPLAY INVISIBLE (-700 2450);
FORCEPROP 2 LAST CD_SEC 1
J 0
(-750 2700);
DISPLAY 1.617021 (-750 2700);
PAINT MONO (-750 2700);
DISPLAY INVISIBLE (-750 2700);
FORCEPROP 2 LAST SIGNAL_MODEL DEFAULT_RESISTOR_750OHM_2_1
J 0
(-750 2700);
DISPLAY 1.617021 (-750 2700);
PAINT MONO (-750 2700);
DISPLAY INVISIBLE (-750 2700);
FORCEPROP 2 LAST BOM_COST SM_CONTROLLER
J 2
(-1275 2550);
DISPLAY 1.617021 (-1275 2550);
PAINT PEACH (-1275 2550);
DISPLAY INVISIBLE (-1275 2550);
FORCEPROP 2 LAST CDS_SEC 1
J 0
(-750 2675);
DISPLAY 1.404255 (-750 2675);
PAINT ORANGE (-750 2675);
DISPLAY INVISIBLE (-750 2675);
FORCEPROP 2 LAST $SEC 1
J 0
(-750 2675);
DISPLAY 0.936170 (-750 2675);
PAINT MONO (-750 2675);
DISPLAY INVISIBLE (-750 2675);
FORCEPROP 2 LAST CDS_LOCATION R6T1
J 2
(-745 2575);
DISPLAY 0.617021 (-745 2575);
PAINT AQUA (-745 2575);
DISPLAY INVISIBLE (-745 2575);
FORCEPROP 1 LAST PATH I70
J 2
(-750 2625);
DISPLAY 0.978723 (-750 2625);
PAINT WHITE (-750 2625);
DISPLAY INVISIBLE (-750 2625);
FORCEPROP 2 LAST ROOM MEM
J 0
(-725 2600);
PAINT MONO (-725 2600);
DISPLAY INVISIBLE (-725 2600);
FORCEADD PVCCIO_CPU1..1
(-950 2775);
FORCEPROP 3 LASTPIN (-950 2725) SIG_NAME PVCCIO_CPU1\g
J 0
(-940 2735);
DISPLAY 0.659574 (-940 2735);
PAINT MONO (-940 2735);
DISPLAY INVISIBLE (-940 2735);
FORCEPROP 1 LAST HDL_POWER PVCCIO_CPU1
J 1
(-950 2825);
DISPLAY 0.872340 (-950 2825);
PAINT GREEN (-950 2825);
DISPLAY INVISIBLE (-950 2825);
FORCEPROP 1 LAST BODY_TYPE PLUMBING
J 0
(-995 2732);
DISPLAY 0.340426 (-995 2732);
PAINT GREEN (-995 2732);
DISPLAY INVISIBLE (-995 2732);
FORCEPROP 1 LAST VOLTAGE 1.1V
J 0
(-995 2732);
DISPLAY 0.340426 (-995 2732);
PAINT SKYBLUE (-995 2732);
DISPLAY INVISIBLE (-995 2732);
FORCEPROP 2 LAST CDS_LIB mstr_symbols
J 0
(-950 2775);
PAINT ORANGE (-950 2775);
DISPLAY INVISIBLE (-950 2775);
FORCEPROP 1 LAST PATH I71
J 0
(-900 2800);
DISPLAY 0.872340 (-900 2800);
PAINT AQUA (-900 2800);
DISPLAY INVISIBLE (-900 2800);
FORCEADD RES..2
R 2
(-1075 2450);
FORCEPROP 1 LAST LOCATION R6T2
J 2
(-1120 2575);
DISPLAY 0.617021 (-1120 2575);
PAINT AQUA (-1120 2575);
FORCEPROP 1 LAST PART_NUMBER G21796-294
J 2
(-1115 2325);
DISPLAY 0.617021 (-1115 2325);
PAINT BLUE (-1115 2325);
FORCEPROP 1 LAST VALUE 240
J 2
(-1120 2525);
DISPLAY 0.617021 (-1120 2525);
PAINT SKYBLUE (-1120 2525);
FORCEPROP 1 LAST TOLERANCE 1.0%
J 2
(-1120 2475);
DISPLAY 0.617021 (-1120 2475);
PAINT SKYBLUE (-1120 2475);
FORCEPROP 1 LAST PACK_TYPE 0402
J 2
(-1115 2275);
DISPLAY 0.617021 (-1115 2275);
PAINT SKYBLUE (-1115 2275);
FORCEPROP 1 LAST MATERIAL CHIP
J 2
(-1115 2375);
DISPLAY 0.617021 (-1115 2375);
PAINT SKYBLUE (-1115 2375);
FORCEPROP 1 LAST WATTAGE 1/16W
J 2
(-1115 2425);
DISPLAY 0.617021 (-1115 2425);
PAINT SKYBLUE (-1115 2425);
FORCEPROP 1 LASTPIN (-1075 2350) $PN 2
J 2
(-1080 2360);
DISPLAY 0.617021 (-1080 2360);
PAINT MONO (-1080 2360);
FORCEPROP 1 LASTPIN (-1075 2550) $PN 1
J 2
(-1080 2512);
DISPLAY 0.617021 (-1080 2512);
PAINT MONO (-1080 2512);
FORCEPROP 2 LAST CDS_LIB mstr_discrete
J 0
(-1075 2450);
PAINT MONO (-1075 2450);
DISPLAY INVISIBLE (-1075 2450);
FORCEPROP 2 LAST SIGNAL_MODEL DEFAULT_RESISTOR_750OHM_2_1
J 0
(-1125 2700);
DISPLAY 1.617021 (-1125 2700);
PAINT MONO (-1125 2700);
DISPLAY INVISIBLE (-1125 2700);
FORCEPROP 2 LAST CD_SEC 1
J 0
(-1125 2700);
DISPLAY 1.617021 (-1125 2700);
PAINT MONO (-1125 2700);
DISPLAY INVISIBLE (-1125 2700);
FORCEPROP 2 LAST BOM_COST SM_CONTROLLER
J 2
(-1650 2550);
DISPLAY 1.617021 (-1650 2550);
PAINT PEACH (-1650 2550);
DISPLAY INVISIBLE (-1650 2550);
FORCEPROP 2 LAST CDS_SEC 1
J 0
(-1125 2675);
DISPLAY 1.404255 (-1125 2675);
PAINT ORANGE (-1125 2675);
DISPLAY INVISIBLE (-1125 2675);
FORCEPROP 2 LAST $SEC 1
J 0
(-1125 2675);
DISPLAY 0.936170 (-1125 2675);
PAINT MONO (-1125 2675);
DISPLAY INVISIBLE (-1125 2675);
FORCEPROP 2 LAST CDS_LOCATION R6T2
J 2
(-1120 2575);
DISPLAY 0.617021 (-1120 2575);
PAINT AQUA (-1120 2575);
DISPLAY INVISIBLE (-1120 2575);
FORCEPROP 1 LAST PATH I72
J 2
(-1125 2625);
DISPLAY 0.978723 (-1125 2625);
PAINT WHITE (-1125 2625);
DISPLAY INVISIBLE (-1125 2625);
FORCEPROP 2 LAST ROOM MEM
J 0
(-1100 2600);
PAINT MONO (-1100 2600);
DISPLAY INVISIBLE (-1100 2600);
FORCEADD PVPP_KLM..1
(575 1225);
FORCEPROP 3 LASTPIN (575 1175) SIG_NAME PVPP_KLM\g
J 0
(585 1185);
DISPLAY 0.659574 (585 1185);
PAINT MONO (585 1185);
DISPLAY INVISIBLE (585 1185);
FORCEPROP 1 LAST HDL_POWER PVPP_KLM
J 1
(575 1275);
DISPLAY 0.872340 (575 1275);
PAINT GREEN (575 1275);
DISPLAY INVISIBLE (575 1275);
FORCEPROP 1 LAST BODY_TYPE PLUMBING
J 0
(530 1182);
DISPLAY 0.340426 (530 1182);
PAINT GREEN (530 1182);
DISPLAY INVISIBLE (530 1182);
FORCEPROP 1 LAST VOLTAGE 2.5V
J 0
(530 1182);
DISPLAY 0.340426 (530 1182);
PAINT SKYBLUE (530 1182);
DISPLAY INVISIBLE (530 1182);
FORCEPROP 2 LAST BOM_COST SM_CONTROLLER
J 0
(575 1325);
DISPLAY 1.617021 (575 1325);
PAINT ORANGE (575 1325);
DISPLAY INVISIBLE (575 1325);
FORCEPROP 2 LAST CDS_LIB mstr_symbols
J 0
(575 1225);
PAINT ORANGE (575 1225);
DISPLAY INVISIBLE (575 1225);
FORCEPROP 1 LAST PATH I74
J 0
(625 1250);
DISPLAY 0.872340 (625 1250);
PAINT AQUA (625 1250);
DISPLAY INVISIBLE (625 1250);
FORCEPROP 2 LAST ROOM SMB
J 0
(575 1300);
PAINT MONO (575 1300);
DISPLAY INVISIBLE (575 1300);
FORCEADD PCA9617..1
(150 900);
FORCEPROP 1 LAST POWER_GROUP GND=GND
J 0
(-200 650);
DISPLAY 0.617021 (-200 650);
PAINT ORANGE (-200 650);
FORCEPROP 1 LAST LOCATION U3B1
J 0
(-200 1225);
DISPLAY 0.617021 (-200 1225);
PAINT AQUA (-200 1225);
FORCEPROP 1 LAST PART_NUMBER G81764-001
J 0
(-200 700);
DISPLAY 0.617021 (-200 700);
PAINT BLUE (-200 700);
FORCEPROP 1 LAST MATERIAL IC
J 0
(-200 1175);
DISPLAY 0.617021 (-200 1175);
PAINT SKYBLUE (-200 1175);
FORCEPROP 2 LASTPIN (550 1050) $PN 8
J 0
(560 1060);
DISPLAY 0.617021 (560 1060);
PAINT MONO (560 1060);
FORCEPROP 2 LASTPIN (-250 1050) $PN 1
J 2
(-260 1060);
DISPLAY 0.617021 (-260 1060);
PAINT MONO (-260 1060);
FORCEPROP 2 LASTPIN (550 900) $PN 6
J 0
(560 910);
DISPLAY 0.617021 (560 910);
PAINT MONO (560 910);
FORCEPROP 2 LASTPIN (-250 900) $PN 3
J 2
(-260 910);
DISPLAY 0.617021 (-260 910);
PAINT MONO (-260 910);
FORCEPROP 2 LASTPIN (550 950) $PN 7
J 0
(560 960);
DISPLAY 0.617021 (560 960);
PAINT MONO (560 960);
FORCEPROP 2 LASTPIN (-250 950) $PN 2
J 2
(-260 960);
DISPLAY 0.617021 (-260 960);
PAINT MONO (-260 960);
FORCEPROP 2 LASTPIN (-250 800) $PN 5
J 2
(-260 810);
DISPLAY 0.617021 (-260 810);
PAINT MONO (-260 810);
FORCEPROP 1 LAST PACK_TYPE SSOP
J 0
(-200 1275);
PAINT SKYBLUE (-200 1275);
DISPLAY INVISIBLE (-200 1275);
FORCEPROP 2 LAST CDS_LIB mstr_digital
J 0
(150 900);
PAINT MONO (150 900);
DISPLAY INVISIBLE (150 900);
FORCEPROP 2 LAST BOM_COST SM_CONTROLLER
J 0
(-200 1275);
PAINT MONO (-200 1275);
DISPLAY INVISIBLE (-200 1275);
FORCEPROP 2 LAST CDS_SEC 1
J 0
(-200 1275);
DISPLAY 1.404255 (-200 1275);
PAINT ORANGE (-200 1275);
DISPLAY INVISIBLE (-200 1275);
FORCEPROP 2 LAST $SEC 1
J 0
(-200 1275);
DISPLAY 0.936170 (-200 1275);
PAINT MONO (-200 1275);
DISPLAY INVISIBLE (-200 1275);
FORCEPROP 2 LAST CDS_LOCATION U3B1
J 0
(-200 1225);
DISPLAY 0.617021 (-200 1225);
PAINT AQUA (-200 1225);
DISPLAY INVISIBLE (-200 1225);
FORCEPROP 1 LAST PATH I75
J 0
(275 1175);
PAINT GREEN (275 1175);
DISPLAY INVISIBLE (275 1175);
FORCEPROP 2 LAST ROOM MEM
J 0
(-200 1275);
PAINT MONO (-200 1275);
DISPLAY INVISIBLE (-200 1275);
FORCEADD PVCCIO_CPU1..1
(-550 1475);
FORCEPROP 3 LASTPIN (-550 1425) SIG_NAME PVCCIO_CPU1\g
J 0
(-540 1435);
DISPLAY 0.659574 (-540 1435);
PAINT MONO (-540 1435);
DISPLAY INVISIBLE (-540 1435);
FORCEPROP 1 LAST HDL_POWER PVCCIO_CPU1
J 1
(-550 1525);
DISPLAY 0.872340 (-550 1525);
PAINT GREEN (-550 1525);
DISPLAY INVISIBLE (-550 1525);
FORCEPROP 1 LAST BODY_TYPE PLUMBING
J 0
(-595 1432);
DISPLAY 0.340426 (-595 1432);
PAINT GREEN (-595 1432);
DISPLAY INVISIBLE (-595 1432);
FORCEPROP 1 LAST VOLTAGE 1.1V
J 0
(-595 1432);
DISPLAY 0.340426 (-595 1432);
PAINT SKYBLUE (-595 1432);
DISPLAY INVISIBLE (-595 1432);
FORCEPROP 2 LAST CDS_LIB mstr_symbols
J 0
(-550 1475);
PAINT ORANGE (-550 1475);
DISPLAY INVISIBLE (-550 1475);
FORCEPROP 1 LAST PATH I76
J 0
(-500 1500);
DISPLAY 0.872340 (-500 1500);
PAINT AQUA (-500 1500);
DISPLAY INVISIBLE (-500 1500);
FORCEADD RES..2
R 2
(-725 1250);
FORCEPROP 1 LAST LOCATION R7M7
J 2
(-770 1375);
DISPLAY 0.617021 (-770 1375);
PAINT AQUA (-770 1375);
FORCEPROP 1 LAST PART_NUMBER G21796-294
J 2
(-765 1125);
DISPLAY 0.617021 (-765 1125);
PAINT BLUE (-765 1125);
FORCEPROP 1 LAST VALUE 240
J 2
(-770 1325);
DISPLAY 0.617021 (-770 1325);
PAINT SKYBLUE (-770 1325);
FORCEPROP 1 LAST TOLERANCE 1.0%
J 2
(-770 1275);
DISPLAY 0.617021 (-770 1275);
PAINT SKYBLUE (-770 1275);
FORCEPROP 1 LAST PACK_TYPE 0402
J 2
(-765 1075);
DISPLAY 0.617021 (-765 1075);
PAINT SKYBLUE (-765 1075);
FORCEPROP 1 LAST MATERIAL CHIP
J 2
(-765 1175);
DISPLAY 0.617021 (-765 1175);
PAINT SKYBLUE (-765 1175);
FORCEPROP 1 LAST WATTAGE 1/16W
J 2
(-765 1225);
DISPLAY 0.617021 (-765 1225);
PAINT SKYBLUE (-765 1225);
FORCEPROP 1 LASTPIN (-725 1150) $PN 2
J 2
(-730 1160);
DISPLAY 0.617021 (-730 1160);
PAINT MONO (-730 1160);
FORCEPROP 1 LASTPIN (-725 1350) $PN 1
J 2
(-730 1312);
DISPLAY 0.617021 (-730 1312);
PAINT MONO (-730 1312);
FORCEPROP 2 LAST CDS_LIB mstr_discrete
J 0
(-725 1250);
PAINT MONO (-725 1250);
DISPLAY INVISIBLE (-725 1250);
FORCEPROP 2 LAST CD_SEC 1
J 0
(-775 1500);
DISPLAY 1.617021 (-775 1500);
PAINT MONO (-775 1500);
DISPLAY INVISIBLE (-775 1500);
FORCEPROP 2 LAST SIGNAL_MODEL DEFAULT_RESISTOR_750OHM_2_1
J 0
(-775 1500);
DISPLAY 1.617021 (-775 1500);
PAINT MONO (-775 1500);
DISPLAY INVISIBLE (-775 1500);
FORCEPROP 2 LAST BOM_COST SM_CONTROLLER
J 2
(-1300 1350);
DISPLAY 1.617021 (-1300 1350);
PAINT PEACH (-1300 1350);
DISPLAY INVISIBLE (-1300 1350);
FORCEPROP 2 LAST CDS_SEC 1
J 0
(-775 1475);
DISPLAY 1.404255 (-775 1475);
PAINT ORANGE (-775 1475);
DISPLAY INVISIBLE (-775 1475);
FORCEPROP 2 LAST $SEC 1
J 0
(-775 1475);
DISPLAY 0.936170 (-775 1475);
PAINT MONO (-775 1475);
DISPLAY INVISIBLE (-775 1475);
FORCEPROP 2 LAST CDS_LOCATION R7M7
J 2
(-770 1375);
DISPLAY 0.617021 (-770 1375);
PAINT AQUA (-770 1375);
DISPLAY INVISIBLE (-770 1375);
FORCEPROP 1 LAST PATH I77
J 2
(-775 1425);
DISPLAY 0.978723 (-775 1425);
PAINT WHITE (-775 1425);
DISPLAY INVISIBLE (-775 1425);
FORCEPROP 2 LAST ROOM MEM
J 0
(-750 1400);
PAINT MONO (-750 1400);
DISPLAY INVISIBLE (-750 1400);
FORCEADD PVCCIO_CPU1..1
(-975 1575);
FORCEPROP 3 LASTPIN (-975 1525) SIG_NAME PVCCIO_CPU1\g
J 0
(-965 1535);
DISPLAY 0.659574 (-965 1535);
PAINT MONO (-965 1535);
DISPLAY INVISIBLE (-965 1535);
FORCEPROP 1 LAST HDL_POWER PVCCIO_CPU1
J 1
(-975 1625);
DISPLAY 0.872340 (-975 1625);
PAINT GREEN (-975 1625);
DISPLAY INVISIBLE (-975 1625);
FORCEPROP 1 LAST BODY_TYPE PLUMBING
J 0
(-1020 1532);
DISPLAY 0.340426 (-1020 1532);
PAINT GREEN (-1020 1532);
DISPLAY INVISIBLE (-1020 1532);
FORCEPROP 1 LAST VOLTAGE 1.1V
J 0
(-1020 1532);
DISPLAY 0.340426 (-1020 1532);
PAINT SKYBLUE (-1020 1532);
DISPLAY INVISIBLE (-1020 1532);
FORCEPROP 2 LAST CDS_LIB mstr_symbols
J 0
(-975 1575);
PAINT ORANGE (-975 1575);
DISPLAY INVISIBLE (-975 1575);
FORCEPROP 1 LAST PATH I78
J 0
(-925 1600);
DISPLAY 0.872340 (-925 1600);
PAINT AQUA (-925 1600);
DISPLAY INVISIBLE (-925 1600);
FORCEADD RES..2
R 2
(-1100 1250);
FORCEPROP 1 LAST LOCATION R7M2
J 2
(-1145 1375);
DISPLAY 0.617021 (-1145 1375);
PAINT AQUA (-1145 1375);
FORCEPROP 1 LAST PART_NUMBER G21796-294
J 2
(-1140 1125);
DISPLAY 0.617021 (-1140 1125);
PAINT BLUE (-1140 1125);
FORCEPROP 1 LAST VALUE 240
J 2
(-1145 1325);
DISPLAY 0.617021 (-1145 1325);
PAINT SKYBLUE (-1145 1325);
FORCEPROP 1 LAST TOLERANCE 1.0%
J 2
(-1145 1275);
DISPLAY 0.617021 (-1145 1275);
PAINT SKYBLUE (-1145 1275);
FORCEPROP 1 LAST PACK_TYPE 0402
J 2
(-1140 1075);
DISPLAY 0.617021 (-1140 1075);
PAINT SKYBLUE (-1140 1075);
FORCEPROP 1 LAST MATERIAL CHIP
J 2
(-1140 1175);
DISPLAY 0.617021 (-1140 1175);
PAINT SKYBLUE (-1140 1175);
FORCEPROP 1 LAST WATTAGE 1/16W
J 2
(-1140 1225);
DISPLAY 0.617021 (-1140 1225);
PAINT SKYBLUE (-1140 1225);
FORCEPROP 1 LASTPIN (-1100 1150) $PN 2
J 2
(-1105 1160);
DISPLAY 0.617021 (-1105 1160);
PAINT MONO (-1105 1160);
FORCEPROP 1 LASTPIN (-1100 1350) $PN 1
J 2
(-1105 1312);
DISPLAY 0.617021 (-1105 1312);
PAINT MONO (-1105 1312);
FORCEPROP 2 LAST CDS_LIB mstr_discrete
J 0
(-1100 1250);
PAINT MONO (-1100 1250);
DISPLAY INVISIBLE (-1100 1250);
FORCEPROP 2 LAST CD_SEC 1
J 0
(-1150 1500);
DISPLAY 1.617021 (-1150 1500);
PAINT MONO (-1150 1500);
DISPLAY INVISIBLE (-1150 1500);
FORCEPROP 2 LAST SIGNAL_MODEL DEFAULT_RESISTOR_750OHM_2_1
J 0
(-1150 1500);
DISPLAY 1.617021 (-1150 1500);
PAINT MONO (-1150 1500);
DISPLAY INVISIBLE (-1150 1500);
FORCEPROP 2 LAST BOM_COST SM_CONTROLLER
J 2
(-1675 1350);
DISPLAY 1.617021 (-1675 1350);
PAINT PEACH (-1675 1350);
DISPLAY INVISIBLE (-1675 1350);
FORCEPROP 2 LAST CDS_SEC 1
J 0
(-1150 1475);
DISPLAY 1.404255 (-1150 1475);
PAINT ORANGE (-1150 1475);
DISPLAY INVISIBLE (-1150 1475);
FORCEPROP 2 LAST $SEC 1
J 0
(-1150 1475);
DISPLAY 0.936170 (-1150 1475);
PAINT MONO (-1150 1475);
DISPLAY INVISIBLE (-1150 1475);
FORCEPROP 2 LAST CDS_LOCATION R7M2
J 2
(-1145 1375);
DISPLAY 0.617021 (-1145 1375);
PAINT AQUA (-1145 1375);
DISPLAY INVISIBLE (-1145 1375);
FORCEPROP 1 LAST PATH I79
J 2
(-1150 1425);
DISPLAY 0.978723 (-1150 1425);
PAINT WHITE (-1150 1425);
DISPLAY INVISIBLE (-1150 1425);
FORCEPROP 2 LAST ROOM MEM
J 0
(-1125 1400);
PAINT MONO (-1125 1400);
DISPLAY INVISIBLE (-1125 1400);
FORCEADD GND..1
(1475 4650);
FORCEPROP 3 LASTPIN (1475 4700) SIG_NAME GND\g
J 0
(1485 4710);
DISPLAY 0.659574 (1485 4710);
PAINT MONO (1485 4710);
DISPLAY INVISIBLE (1485 4710);
FORCEPROP 1 LAST HDL_POWER GND
J 0
(1475 4800);
DISPLAY 2.361702 (1475 4800);
PAINT GREEN (1475 4800);
DISPLAY INVISIBLE (1475 4800);
FORCEPROP 1 LAST BODY_TYPE PLUMBING
J 0
(1430 4607);
DISPLAY 0.340426 (1430 4607);
PAINT GREEN (1430 4607);
DISPLAY INVISIBLE (1430 4607);
FORCEPROP 1 LAST VOLTAGE 0
J 0
(1475 4650);
PAINT SKYBLUE (1475 4650);
DISPLAY INVISIBLE (1475 4650);
FORCEPROP 2 LAST BOM_COST SM_CONTROLLER
J 0
(1075 4725);
DISPLAY 1.617021 (1075 4725);
PAINT ORANGE (1075 4725);
DISPLAY INVISIBLE (1075 4725);
FORCEPROP 2 LAST CDS_LIB mstr_symbols
J 0
(1475 4650);
PAINT MONO (1475 4650);
DISPLAY INVISIBLE (1475 4650);
FORCEPROP 1 LAST SIZE 1B
J 0
(1550 4600);
DISPLAY 2.361702 (1550 4600);
PAINT GREEN (1550 4600);
DISPLAY INVISIBLE (1550 4600);
FORCEPROP 1 LAST PATH I8
J 0
(1550 4650);
DISPLAY 0.872340 (1550 4650);
PAINT AQUA (1550 4650);
DISPLAY INVISIBLE (1550 4650);
FORCEPROP 2 LAST ROOM SMB
J 0
(1375 4725);
PAINT MONO (1375 4725);
DISPLAY INVISIBLE (1375 4725);
FORCEADD RES..1
(-1500 4350);
FORCEPROP 1 LAST LOCATION R4T3
J 0
(-1550 4400);
DISPLAY 0.617021 (-1550 4400);
PAINT AQUA (-1550 4400);
FORCEPROP 1 LAST PART_NUMBER G21796-066
J 0
(-1825 4400);
DISPLAY 0.617021 (-1825 4400);
PAINT BLUE (-1825 4400);
FORCEPROP 1 LAST VALUE 10.0
J 2
(-1300 4350);
DISPLAY 0.617021 (-1300 4350);
PAINT SKYBLUE (-1300 4350);
FORCEPROP 1 LAST TOLERANCE 1%
J 0
(-1425 4250);
DISPLAY 0.617021 (-1425 4250);
PAINT SKYBLUE (-1425 4250);
FORCEPROP 1 LAST PACK_TYPE 0402
J 0
(-1675 4200);
DISPLAY 0.617021 (-1675 4200);
PAINT SKYBLUE (-1675 4200);
FORCEPROP 1 LAST MATERIAL CHIP
J 0
(-1550 4250);
DISPLAY 0.617021 (-1550 4250);
PAINT SKYBLUE (-1550 4250);
FORCEPROP 1 LAST WATTAGE 1/16W
J 2
(-1575 4250);
DISPLAY 0.617021 (-1575 4250);
PAINT SKYBLUE (-1575 4250);
FORCEPROP 1 LASTPIN (-1400 4350) $PN 2
J 0
(-1438 4362);
DISPLAY 0.617021 (-1438 4362);
PAINT MONO (-1438 4362);
FORCEPROP 1 LASTPIN (-1600 4350) $PN 1
J 0
(-1588 4362);
DISPLAY 0.617021 (-1588 4362);
PAINT MONO (-1588 4362);
FORCEPROP 2 LAST BOM_COST SM_CONTROLLER
J 0
(-1550 4450);
PAINT MONO (-1550 4450);
DISPLAY INVISIBLE (-1550 4450);
FORCEPROP 2 LAST CDS_LIB mstr_discrete
J 0
(-1500 4350);
PAINT MONO (-1500 4350);
DISPLAY INVISIBLE (-1500 4350);
FORCEPROP 2 LAST CDS_SEC 1
J 0
(-1550 4550);
DISPLAY 1.404255 (-1550 4550);
PAINT ORANGE (-1550 4550);
DISPLAY INVISIBLE (-1550 4550);
FORCEPROP 2 LAST $SEC 1
J 0
(-1550 4550);
DISPLAY 0.936170 (-1550 4550);
PAINT MONO (-1550 4550);
DISPLAY INVISIBLE (-1550 4550);
FORCEPROP 2 LAST CDS_LOCATION R4T3
J 0
(-1550 4400);
DISPLAY 0.617021 (-1550 4400);
PAINT AQUA (-1550 4400);
DISPLAY INVISIBLE (-1550 4400);
FORCEPROP 1 LAST PATH I83
J 0
(-1550 4500);
DISPLAY 0.978723 (-1550 4500);
PAINT WHITE (-1550 4500);
DISPLAY INVISIBLE (-1550 4500);
FORCEPROP 2 LAST ROOM MEM
J 0
(-1550 4450);
PAINT MONO (-1550 4450);
DISPLAY INVISIBLE (-1550 4450);
FORCEADD OFFPAGE..1
(-2325 4350);
FORCEPROP 2 LAST $XR0 21 
J 0
(-2546 4350);
DISPLAY 0.638298 (-2546 4350);
PAINT MONO (-2546 4350);
FORCEPROP 1 LAST COMMENT_BODY TRUE
J 0
(-2200 4250);
DISPLAY 0.872340 (-2200 4250);
PAINT GREEN (-2200 4250);
DISPLAY INVISIBLE (-2200 4250);
FORCEPROP 1 LAST OFFPAGE TRUE
J 0
(-2000 4225);
PAINT GREEN (-2000 4225);
DISPLAY INVISIBLE (-2000 4225);
FORCEPROP 2 LAST BOM_COST SM_CONTROLLER
J 0
(-2575 4400);
PAINT MONO (-2575 4400);
DISPLAY INVISIBLE (-2575 4400);
FORCEPROP 2 LAST CDS_LIB mstr_standard
J 0
(-2325 4350);
PAINT ORANGE (-2325 4350);
DISPLAY INVISIBLE (-2325 4350);
FORCEPROP 2 LAST ROOM SMB
J 0
(-2575 4400);
PAINT MONO (-2575 4400);
DISPLAY INVISIBLE (-2575 4400);
FORCEPROP 2 LAST PATH I84
J 0
(-2525 4400);
DISPLAY 1.021277 (-2525 4400);
PAINT ORANGE (-2525 4400);
DISPLAY INVISIBLE (-2525 4400);
FORCEADD OFFPAGE..6
(-2325 4300);
FORCEPROP 2 LAST $XR0 21 
J 0
(-2604 4300);
DISPLAY 0.638298 (-2604 4300);
PAINT MONO (-2604 4300);
FORCEPROP 2 LASTPIN (-2275 4300) SIG_NAME SMB_DDR_ABC_SDA_G_R
J 0
(-2210 4310);
DISPLAY 0.617021 (-2210 4310);
PAINT ORANGE (-2210 4310);
FORCEPROP 1 LAST COMMENT_BODY TRUE
J 0
(-2225 4225);
DISPLAY 1.872340 (-2225 4225);
PAINT GREEN (-2225 4225);
DISPLAY INVISIBLE (-2225 4225);
FORCEPROP 1 LAST OFFPAGE TRUE
J 0
(-2000 4175);
PAINT GREEN (-2000 4175);
DISPLAY INVISIBLE (-2000 4175);
FORCEPROP 2 LAST BOM_COST SM_CONTROLLER
J 0
(-2550 4350);
DISPLAY 1.617021 (-2550 4350);
PAINT ORANGE (-2550 4350);
DISPLAY INVISIBLE (-2550 4350);
FORCEPROP 2 LAST CDS_LIB mstr_standard
J 0
(-2325 4300);
PAINT MONO (-2325 4300);
DISPLAY INVISIBLE (-2325 4300);
FORCEPROP 2 LAST PATH I85
J 0
(-2600 4350);
DISPLAY 1.021277 (-2600 4350);
PAINT ORANGE (-2600 4350);
DISPLAY INVISIBLE (-2600 4350);
FORCEADD RES..1
(-1575 3300);
FORCEPROP 1 LAST LOCATION R3R7
J 0
(-1625 3350);
DISPLAY 0.617021 (-1625 3350);
PAINT AQUA (-1625 3350);
FORCEPROP 1 LAST PART_NUMBER G21796-066
J 0
(-1875 3375);
DISPLAY 0.617021 (-1875 3375);
PAINT BLUE (-1875 3375);
FORCEPROP 1 LAST VALUE 10.0
J 2
(-1400 3300);
DISPLAY 0.617021 (-1400 3300);
PAINT SKYBLUE (-1400 3300);
FORCEPROP 1 LAST TOLERANCE 1%
J 0
(-1475 3200);
DISPLAY 0.617021 (-1475 3200);
PAINT SKYBLUE (-1475 3200);
FORCEPROP 1 LAST PACK_TYPE 0402
J 0
(-1725 3150);
DISPLAY 0.617021 (-1725 3150);
PAINT SKYBLUE (-1725 3150);
FORCEPROP 1 LAST MATERIAL CHIP
J 0
(-1600 3200);
DISPLAY 0.617021 (-1600 3200);
PAINT SKYBLUE (-1600 3200);
FORCEPROP 1 LAST WATTAGE 1/16W
J 2
(-1625 3200);
DISPLAY 0.617021 (-1625 3200);
PAINT SKYBLUE (-1625 3200);
FORCEPROP 1 LASTPIN (-1475 3300) $PN 2
J 0
(-1513 3312);
DISPLAY 0.617021 (-1513 3312);
PAINT MONO (-1513 3312);
FORCEPROP 1 LASTPIN (-1675 3300) $PN 1
J 0
(-1663 3312);
DISPLAY 0.617021 (-1663 3312);
PAINT MONO (-1663 3312);
FORCEPROP 2 LAST CDS_LIB mstr_discrete
J 0
(-1575 3300);
PAINT MONO (-1575 3300);
DISPLAY INVISIBLE (-1575 3300);
FORCEPROP 2 LAST BOM_COST SM_CONTROLLER
J 0
(-1625 3400);
PAINT MONO (-1625 3400);
DISPLAY INVISIBLE (-1625 3400);
FORCEPROP 2 LAST CDS_SEC 1
J 0
(-1625 3500);
DISPLAY 1.404255 (-1625 3500);
PAINT ORANGE (-1625 3500);
DISPLAY INVISIBLE (-1625 3500);
FORCEPROP 2 LAST $SEC 1
J 0
(-1625 3500);
DISPLAY 0.936170 (-1625 3500);
PAINT MONO (-1625 3500);
DISPLAY INVISIBLE (-1625 3500);
FORCEPROP 2 LAST CDS_LOCATION R3R7
J 0
(-1625 3350);
DISPLAY 0.617021 (-1625 3350);
PAINT AQUA (-1625 3350);
DISPLAY INVISIBLE (-1625 3350);
FORCEPROP 1 LAST PATH I88
J 0
(-1625 3450);
DISPLAY 0.978723 (-1625 3450);
PAINT WHITE (-1625 3450);
DISPLAY INVISIBLE (-1625 3450);
FORCEPROP 2 LAST ROOM MEM
J 0
(-1625 3400);
PAINT MONO (-1625 3400);
DISPLAY INVISIBLE (-1625 3400);
FORCEADD OFFPAGE..1
(-2350 3300);
FORCEPROP 2 LAST $XR0 21 
J 0
(-2571 3300);
DISPLAY 0.638298 (-2571 3300);
PAINT MONO (-2571 3300);
FORCEPROP 1 LAST COMMENT_BODY TRUE
J 0
(-2225 3200);
DISPLAY 0.872340 (-2225 3200);
PAINT GREEN (-2225 3200);
DISPLAY INVISIBLE (-2225 3200);
FORCEPROP 1 LAST OFFPAGE TRUE
J 0
(-2025 3175);
PAINT GREEN (-2025 3175);
DISPLAY INVISIBLE (-2025 3175);
FORCEPROP 2 LAST CDS_LIB mstr_standard
J 0
(-2350 3300);
PAINT ORANGE (-2350 3300);
DISPLAY INVISIBLE (-2350 3300);
FORCEPROP 2 LAST BOM_COST SM_CONTROLLER
J 0
(-2600 3350);
PAINT MONO (-2600 3350);
DISPLAY INVISIBLE (-2600 3350);
FORCEPROP 2 LAST ROOM SMB
J 0
(-2600 3350);
PAINT MONO (-2600 3350);
DISPLAY INVISIBLE (-2600 3350);
FORCEPROP 2 LAST PATH I89
J 0
(-2550 3350);
DISPLAY 1.021277 (-2550 3350);
PAINT ORANGE (-2550 3350);
DISPLAY INVISIBLE (-2550 3350);
FORCEADD RES..1
(1600 4350);
FORCEPROP 1 LAST LOCATION R4T9
J 0
(1550 4425);
DISPLAY 0.617021 (1550 4425);
PAINT AQUA (1550 4425);
FORCEPROP 1 LAST PART_NUMBER G21796-173
J 0
(1850 4500);
DISPLAY 0.617021 (1850 4500);
PAINT BLUE (1850 4500);
FORCEPROP 1 LAST VALUE 20.0
J 2
(1550 4400);
DISPLAY 0.617021 (1550 4400);
PAINT SKYBLUE (1550 4400);
FORCEPROP 1 LAST TOLERANCE 1%
J 0
(1875 4400);
DISPLAY 0.617021 (1875 4400);
PAINT SKYBLUE (1875 4400);
FORCEPROP 1 LAST PACK_TYPE 0402
J 0
(1650 4400);
DISPLAY 0.617021 (1650 4400);
PAINT SKYBLUE (1650 4400);
FORCEPROP 1 LAST MATERIAL CHIP
J 0
(2000 4450);
DISPLAY 0.617021 (2000 4450);
PAINT SKYBLUE (2000 4450);
FORCEPROP 1 LAST WATTAGE 1/16W
J 2
(2000 4450);
DISPLAY 0.617021 (2000 4450);
PAINT SKYBLUE (2000 4450);
FORCEPROP 1 LASTPIN (1700 4350) $PN 2
J 0
(1662 4362);
DISPLAY 0.617021 (1662 4362);
PAINT MONO (1662 4362);
FORCEPROP 1 LASTPIN (1500 4350) $PN 1
J 0
(1512 4362);
DISPLAY 0.617021 (1512 4362);
PAINT MONO (1512 4362);
FORCEPROP 2 LAST CDS_LIB mstr_discrete
J 0
(1600 4350);
PAINT ORANGE (1600 4350);
DISPLAY INVISIBLE (1600 4350);
FORCEPROP 2 LAST CDS_SEC 1
J 0
(1550 4550);
DISPLAY 1.404255 (1550 4550);
PAINT ORANGE (1550 4550);
DISPLAY INVISIBLE (1550 4550);
FORCEPROP 2 LAST $SEC 1
J 0
(1550 4550);
DISPLAY 0.936170 (1550 4550);
PAINT MONO (1550 4550);
DISPLAY INVISIBLE (1550 4550);
FORCEPROP 2 LAST CDS_LOCATION R4T9
J 0
(1550 4425);
DISPLAY 0.617021 (1550 4425);
PAINT AQUA (1550 4425);
DISPLAY INVISIBLE (1550 4425);
FORCEPROP 1 LAST PATH I9
J 0
(1550 4500);
DISPLAY 0.978723 (1550 4500);
PAINT WHITE (1550 4500);
DISPLAY INVISIBLE (1550 4500);
FORCEPROP 2 LAST ROOM MEM
J 0
(1800 4450);
DISPLAY 1.404255 (1800 4450);
PAINT ORANGE (1800 4450);
DISPLAY INVISIBLE (1800 4450);
FORCEADD RES..1
(-1475 2150);
FORCEPROP 1 LAST LOCATION R6T3
J 0
(-1525 2200);
DISPLAY 0.617021 (-1525 2200);
PAINT AQUA (-1525 2200);
FORCEPROP 1 LAST PART_NUMBER G21796-066
J 0
(-1800 2200);
DISPLAY 0.617021 (-1800 2200);
PAINT BLUE (-1800 2200);
FORCEPROP 1 LAST VALUE 10.0
J 2
(-1300 2150);
DISPLAY 0.617021 (-1300 2150);
PAINT SKYBLUE (-1300 2150);
FORCEPROP 1 LAST TOLERANCE 1%
J 0
(-1400 2050);
DISPLAY 0.617021 (-1400 2050);
PAINT SKYBLUE (-1400 2050);
FORCEPROP 1 LAST PACK_TYPE 0402
J 0
(-1650 2000);
DISPLAY 0.617021 (-1650 2000);
PAINT SKYBLUE (-1650 2000);
FORCEPROP 1 LAST MATERIAL CHIP
J 0
(-1525 2050);
DISPLAY 0.617021 (-1525 2050);
PAINT SKYBLUE (-1525 2050);
FORCEPROP 1 LAST WATTAGE 1/16W
J 2
(-1550 2050);
DISPLAY 0.617021 (-1550 2050);
PAINT SKYBLUE (-1550 2050);
FORCEPROP 1 LASTPIN (-1375 2150) $PN 2
J 0
(-1413 2162);
DISPLAY 0.617021 (-1413 2162);
PAINT MONO (-1413 2162);
FORCEPROP 1 LASTPIN (-1575 2150) $PN 1
J 0
(-1563 2162);
DISPLAY 0.617021 (-1563 2162);
PAINT MONO (-1563 2162);
FORCEPROP 2 LAST CDS_LIB mstr_discrete
J 0
(-1475 2150);
PAINT MONO (-1475 2150);
DISPLAY INVISIBLE (-1475 2150);
FORCEPROP 2 LAST BOM_COST SM_CONTROLLER
J 0
(-1525 2250);
PAINT MONO (-1525 2250);
DISPLAY INVISIBLE (-1525 2250);
FORCEPROP 2 LAST CDS_SEC 1
J 0
(-1525 2350);
DISPLAY 1.404255 (-1525 2350);
PAINT ORANGE (-1525 2350);
DISPLAY INVISIBLE (-1525 2350);
FORCEPROP 2 LAST $SEC 1
J 0
(-1525 2350);
DISPLAY 0.936170 (-1525 2350);
PAINT MONO (-1525 2350);
DISPLAY INVISIBLE (-1525 2350);
FORCEPROP 2 LAST CDS_LOCATION R6T3
J 0
(-1525 2200);
DISPLAY 0.617021 (-1525 2200);
PAINT AQUA (-1525 2200);
DISPLAY INVISIBLE (-1525 2200);
FORCEPROP 1 LAST PATH I92
J 0
(-1525 2300);
DISPLAY 0.978723 (-1525 2300);
PAINT WHITE (-1525 2300);
DISPLAY INVISIBLE (-1525 2300);
FORCEPROP 2 LAST ROOM MEM
J 0
(-1525 2250);
PAINT MONO (-1525 2250);
DISPLAY INVISIBLE (-1525 2250);
FORCEADD OFFPAGE..6
(-2350 3250);
FORCEPROP 2 LAST $XR0 21 
J 0
(-2629 3250);
DISPLAY 0.638298 (-2629 3250);
PAINT MONO (-2629 3250);
FORCEPROP 2 LASTPIN (-2300 3250) SIG_NAME SMB_DDR_DEF_SDA_G_R
J 0
(-2235 3260);
DISPLAY 0.617021 (-2235 3260);
PAINT ORANGE (-2235 3260);
FORCEPROP 1 LAST COMMENT_BODY TRUE
J 0
(-2250 3175);
DISPLAY 1.872340 (-2250 3175);
PAINT GREEN (-2250 3175);
DISPLAY INVISIBLE (-2250 3175);
FORCEPROP 1 LAST OFFPAGE TRUE
J 0
(-2025 3125);
PAINT GREEN (-2025 3125);
DISPLAY INVISIBLE (-2025 3125);
FORCEPROP 2 LAST BOM_COST SM_CONTROLLER
J 0
(-2575 3300);
DISPLAY 1.617021 (-2575 3300);
PAINT ORANGE (-2575 3300);
DISPLAY INVISIBLE (-2575 3300);
FORCEPROP 2 LAST CDS_LIB mstr_standard
J 0
(-2350 3250);
PAINT MONO (-2350 3250);
DISPLAY INVISIBLE (-2350 3250);
FORCEPROP 2 LAST PATH I93
J 0
(-2625 3300);
DISPLAY 1.021277 (-2625 3300);
PAINT ORANGE (-2625 3300);
DISPLAY INVISIBLE (-2625 3300);
FORCEADD OFFPAGE..6
(-2375 2100);
FORCEPROP 2 LAST $XR0 55 
J 0
(-2624 2100);
DISPLAY 0.638298 (-2624 2100);
PAINT MONO (-2624 2100);
FORCEPROP 1 LAST COMMENT_BODY TRUE
J 0
(-2275 2025);
DISPLAY 1.872340 (-2275 2025);
PAINT GREEN (-2275 2025);
DISPLAY INVISIBLE (-2275 2025);
FORCEPROP 1 LAST OFFPAGE TRUE
J 0
(-2050 1975);
PAINT GREEN (-2050 1975);
DISPLAY INVISIBLE (-2050 1975);
FORCEPROP 2 LAST BOM_COST SM_CONTROLLER
J 0
(-2600 2150);
DISPLAY 1.617021 (-2600 2150);
PAINT ORANGE (-2600 2150);
DISPLAY INVISIBLE (-2600 2150);
FORCEPROP 2 LAST CDS_LIB mstr_standard
J 0
(-2375 2100);
PAINT MONO (-2375 2100);
DISPLAY INVISIBLE (-2375 2100);
FORCEPROP 2 LAST PATH I94
J 0
(-2600 2150);
DISPLAY 1.021277 (-2600 2150);
PAINT ORANGE (-2600 2150);
DISPLAY INVISIBLE (-2600 2150);
FORCEADD OFFPAGE..1
(-2375 2150);
FORCEPROP 2 LAST $XR0 55 
J 0
(-2596 2150);
DISPLAY 0.638298 (-2596 2150);
PAINT MONO (-2596 2150);
FORCEPROP 1 LAST COMMENT_BODY TRUE
J 0
(-2250 2050);
DISPLAY 0.872340 (-2250 2050);
PAINT GREEN (-2250 2050);
DISPLAY INVISIBLE (-2250 2050);
FORCEPROP 1 LAST OFFPAGE TRUE
J 0
(-2050 2025);
PAINT GREEN (-2050 2025);
DISPLAY INVISIBLE (-2050 2025);
FORCEPROP 2 LAST BOM_COST SM_CONTROLLER
J 0
(-2625 2200);
PAINT MONO (-2625 2200);
DISPLAY INVISIBLE (-2625 2200);
FORCEPROP 2 LAST CDS_LIB mstr_standard
J 0
(-2375 2150);
PAINT ORANGE (-2375 2150);
DISPLAY INVISIBLE (-2375 2150);
FORCEPROP 2 LAST ROOM SMB
J 0
(-2625 2200);
PAINT MONO (-2625 2200);
DISPLAY INVISIBLE (-2625 2200);
FORCEPROP 2 LAST PATH I95
J 0
(-2575 2200);
DISPLAY 1.021277 (-2575 2200);
PAINT ORANGE (-2575 2200);
DISPLAY INVISIBLE (-2575 2200);
FORCEADD RES..1
(-1575 950);
FORCEPROP 1 LAST LOCATION R7M3
J 0
(-1625 1000);
DISPLAY 0.617021 (-1625 1000);
PAINT AQUA (-1625 1000);
FORCEPROP 1 LAST PART_NUMBER G21796-066
J 0
(-1925 1000);
DISPLAY 0.617021 (-1925 1000);
PAINT BLUE (-1925 1000);
FORCEPROP 1 LAST VALUE 10.0
J 2
(-1375 950);
DISPLAY 0.617021 (-1375 950);
PAINT SKYBLUE (-1375 950);
FORCEPROP 1 LAST TOLERANCE 1%
J 0
(-1500 850);
DISPLAY 0.617021 (-1500 850);
PAINT SKYBLUE (-1500 850);
FORCEPROP 1 LAST PACK_TYPE 0402
J 0
(-1725 800);
DISPLAY 0.617021 (-1725 800);
PAINT SKYBLUE (-1725 800);
FORCEPROP 1 LAST MATERIAL CHIP
J 0
(-1625 850);
DISPLAY 0.617021 (-1625 850);
PAINT SKYBLUE (-1625 850);
FORCEPROP 1 LAST WATTAGE 1/16W
J 2
(-1625 850);
DISPLAY 0.617021 (-1625 850);
PAINT SKYBLUE (-1625 850);
FORCEPROP 1 LASTPIN (-1475 950) $PN 2
J 0
(-1513 962);
DISPLAY 0.617021 (-1513 962);
PAINT MONO (-1513 962);
FORCEPROP 1 LASTPIN (-1675 950) $PN 1
J 0
(-1663 962);
DISPLAY 0.617021 (-1663 962);
PAINT MONO (-1663 962);
FORCEPROP 2 LAST BOM_COST SM_CONTROLLER
J 0
(-1625 1050);
PAINT MONO (-1625 1050);
DISPLAY INVISIBLE (-1625 1050);
FORCEPROP 2 LAST CDS_LIB mstr_discrete
J 0
(-1575 950);
PAINT MONO (-1575 950);
DISPLAY INVISIBLE (-1575 950);
FORCEPROP 2 LAST CDS_SEC 1
J 0
(-1625 1150);
DISPLAY 1.404255 (-1625 1150);
PAINT ORANGE (-1625 1150);
DISPLAY INVISIBLE (-1625 1150);
FORCEPROP 2 LAST $SEC 1
J 0
(-1625 1150);
DISPLAY 0.936170 (-1625 1150);
PAINT MONO (-1625 1150);
DISPLAY INVISIBLE (-1625 1150);
FORCEPROP 2 LAST CDS_LOCATION R7M3
J 0
(-1625 1000);
DISPLAY 0.617021 (-1625 1000);
PAINT AQUA (-1625 1000);
DISPLAY INVISIBLE (-1625 1000);
FORCEPROP 1 LAST PATH I98
J 0
(-1625 1100);
DISPLAY 0.978723 (-1625 1100);
PAINT WHITE (-1625 1100);
DISPLAY INVISIBLE (-1625 1100);
FORCEPROP 2 LAST ROOM MEM
J 0
(-1625 1050);
PAINT MONO (-1625 1050);
DISPLAY INVISIBLE (-1625 1050);
FORCEADD OFFPAGE..1
(-2400 950);
FORCEPROP 2 LAST $XR0 55 
J 0
(-2651 950);
DISPLAY 0.638298 (-2651 950);
PAINT MONO (-2651 950);
FORCEPROP 1 LAST COMMENT_BODY TRUE
J 0
(-2275 850);
DISPLAY 0.872340 (-2275 850);
PAINT GREEN (-2275 850);
DISPLAY INVISIBLE (-2275 850);
FORCEPROP 1 LAST OFFPAGE TRUE
J 0
(-2075 825);
PAINT GREEN (-2075 825);
DISPLAY INVISIBLE (-2075 825);
FORCEPROP 2 LAST BOM_COST SM_CONTROLLER
J 0
(-2650 1000);
PAINT MONO (-2650 1000);
DISPLAY INVISIBLE (-2650 1000);
FORCEPROP 2 LAST CDS_LIB mstr_standard
J 0
(-2400 950);
PAINT ORANGE (-2400 950);
DISPLAY INVISIBLE (-2400 950);
FORCEPROP 2 LAST ROOM SMB
J 0
(-2650 1000);
PAINT MONO (-2650 1000);
DISPLAY INVISIBLE (-2650 1000);
FORCEPROP 2 LAST PATH I99
J 0
(-2650 1000);
DISPLAY 1.021277 (-2650 1000);
PAINT ORANGE (-2650 1000);
DISPLAY INVISIBLE (-2650 1000);
FORCEADD INTEL_CORP_BPAGE..1
(4250 200);
FORCEPROP 1 LAST CDS_CON_LAST_MODIFIED Tue Dec 01 11:51:50 2015
J 0
(2825 525);
PAINT ORANGE (2825 525);
DISPLAY INVISIBLE (2825 525);
FORCEPROP 1 LAST CUSTOM_TXT_CDS <CURRENT_DESIGN_SHEET> OF <TOTAL_DESIGN_SHEETS>
J 0
(3750 225);
PAINT GREEN (3750 225);
FORCEPROP 1 LAST CUSTOM_TXT_CDS <CON_LAST_MODIFIED>
J 0
(2325 550);
PAINT GREEN (2325 550);
FORCEPROP 2 LAST CUSTOM_TXT_CDS <XR_PAGE_TITLE>
J 0
(-3640 5450);
DISPLAY 0.638298 (-3640 5450);
PAINT PINK (-3640 5450);
DISPLAY INVISIBLE (-3640 5450);
FORCEPROP 1 LAST SCH_ADDRESS3 Santa Clara, CA 95052-8119
J 0
(275 225);
DISPLAY 0.617021 (275 225);
PAINT GREEN (275 225);
FORCEPROP 1 LAST SCH_ADDRESS2 P.O. BOX 58119
J 0
(275 275);
DISPLAY 0.617021 (275 275);
PAINT GREEN (275 275);
FORCEPROP 1 LAST SCH_ADDRESS1 2200 Mission College Blvd.
J 0
(275 325);
DISPLAY 0.617021 (275 325);
PAINT GREEN (275 325);
FORCEPROP 1 LAST SCH_TITLE CPU SIDE BAND:DIMM SMBUS TRANSLATORS
J 0
(-3700 250);
DISPLAY 1.212766 (-3700 250);
PAINT ORANGE (-3700 250);
FORCEPROP 1 LAST SCH_NUMBER H4694802
J 0
(2950 350);
DISPLAY 1.212766 (2950 350);
PAINT YELLOW (2950 350);
FORCEPROP 1 LAST SCH_DEPT BESD
J 1
(-200 300);
DISPLAY 1.212766 (-200 300);
PAINT YELLOW (-200 300);
FORCEPROP 1 LAST SCH_REV 2.420
J 0
(4000 350);
DISPLAY 0.978723 (4000 350);
PAINT YELLOW (4000 350);
FORCEPROP 1 LAST COMMENT_BODY TRUE
J 0
(4262 212);
DISPLAY 0.468085 (4262 212);
PAINT GREEN (4262 212);
DISPLAY INVISIBLE (4262 212);
FORCEPROP 2 LAST CDS_LIB mstr_symbols
J 0
(4250 200);
PAINT MONO (4250 200);
DISPLAY INVISIBLE (4250 200);
FORCEPROP 2 LAST PAGE_BORDER TRUE
J 0
(-3640 5450);
DISPLAY 0.638298 (-3640 5450);
PAINT PINK (-3640 5450);
DISPLAY INVISIBLE (-3640 5450);
FORCEPROP 2 LAST CDS_XR_PAGE_TITLE CR-99 : @BASEBOARD_FAB2_LIB.BASEBOARD_FAB2(SCH_1):PAGE99
J 0
(-3640 5450);
DISPLAY 0.638298 (-3640 5450);
PAINT PINK (-3640 5450);
DISPLAY INVISIBLE (-3640 5450);
WIRE 16 -1 (1900 5025)(1900 5050);
WIRE 16 -1 (1275 3700)(1275 3825);
WIRE 16 -1 (1275 3825)(925 3825);
WIRE 16 -1 (925 3700)(925 3825);
WIRE 16 -1 (925 3825)(925 3850);
WIRE 16 -1 (1225 2550)(1225 2675);
WIRE 16 -1 (1225 2675)(875 2675);
WIRE 16 -1 (875 2550)(875 2675);
WIRE 16 -1 (875 2675)(875 2700);
WIRE 16 -1 (1225 1350)(1225 1475);
WIRE 16 -1 (1225 1475)(875 1475);
WIRE 16 -1 (875 1350)(875 1475);
WIRE 16 -1 (875 1475)(875 1500);
WIRE 16 -1 (1475 5000)(1475 5050);
WIRE 16 -1 (550 4450)(650 4450);
WIRE 16 -1 (650 4450)(650 4575);
WIRE 16 -1 (1225 4750)(1225 4875);
WIRE 16 -1 (1225 4875)(875 4875);
WIRE 16 -1 (875 4750)(875 4875);
WIRE 16 -1 (875 4875)(875 4900);
WIRE 16 -1 (-250 4450)(-475 4450);
WIRE 16 -1 (-475 4450)(-475 4825);
WIRE 16 -1 (-650 4750)(-650 4875);
WIRE 16 -1 (-650 4875)(-900 4875);
WIRE 16 -1 (-900 4875)(-1025 4875);
WIRE 16 -1 (-900 4875)(-900 4925);
WIRE 16 -1 (-1025 4750)(-1025 4875);
WIRE 16 -1 (2125 3875)(2125 3900);
WIRE 16 -1 (2125 3675)(2125 3575);
WIRE 16 -1 (2225 2800)(2225 2825);
WIRE 16 -1 (2225 2600)(2225 2500);
WIRE 16 -1 (1900 4825)(1900 4725);
WIRE 16 -1 (1625 3850)(1625 3900);
WIRE 16 -1 (1625 3650)(1625 3550);
WIRE 16 -1 (1650 2775)(1650 2825);
WIRE 16 -1 (1650 2575)(1650 2475);
WIRE 16 -1 (2250 1625)(2250 1650);
WIRE 16 -1 (2250 1425)(2250 1325);
WIRE 16 -1 (1675 1600)(1675 1650);
WIRE 16 -1 (1675 1400)(1675 1300);
WIRE 16 -1 (550 3400)(625 3400);
WIRE 16 -1 (625 3400)(625 3525);
WIRE 16 -1 (550 2250)(600 2250);
WIRE 16 -1 (600 2250)(600 2375);
WIRE 16 -1 (-250 3400)(-500 3400);
WIRE 16 -1 (-500 3400)(-500 3775);
WIRE 16 -1 (-675 3700)(-675 3825);
WIRE 16 -1 (-675 3825)(-925 3825);
WIRE 16 -1 (-925 3825)(-1050 3825);
WIRE 16 -1 (-925 3825)(-925 3875);
WIRE 16 -1 (-1050 3700)(-1050 3825);
WIRE 16 -1 (-250 2250)(-525 2250);
WIRE 16 -1 (-525 2250)(-525 2625);
WIRE 16 -1 (-700 2550)(-700 2675);
WIRE 16 -1 (-700 2675)(-950 2675);
WIRE 16 -1 (-950 2675)(-1075 2675);
WIRE 16 -1 (-950 2675)(-950 2725);
WIRE 16 -1 (-1075 2550)(-1075 2675);
WIRE 16 -1 (550 1050)(575 1050);
WIRE 16 -1 (575 1050)(575 1175);
WIRE 16 -1 (-250 1050)(-550 1050);
WIRE 16 -1 (-550 1050)(-550 1425);
WIRE 16 -1 (-725 1350)(-725 1475);
WIRE 16 -1 (-725 1475)(-975 1475);
WIRE 16 -1 (-975 1475)(-1100 1475);
WIRE 16 -1 (-975 1475)(-975 1525);
WIRE 16 -1 (-1100 1350)(-1100 1475);
WIRE 16 -1 (1475 4800)(1475 4700);
WIRE 16 -1 (1700 4300)(2550 4300);
WIRE 16 -1 (1700 4350)(2550 4350);
FORCEPROP 2 LAST SIG_NAME SMB_DDR_ABC_VPP_SCL
J 0
(1890 4360);
DISPLAY 0.617021 (1890 4360);
PAINT ORANGE (1890 4360);
WIRE 16 -1 (1225 4550)(1225 4300);
WIRE 16 -1 (1225 4300)(1500 4300);
WIRE 16 -1 (550 4300)(1225 4300);
FORCEPROP 2 LAST SIG_NAME SMB_DDR_ABC_VPP_SDA_R
J 0
(640 4310);
DISPLAY 0.617021 (640 4310);
PAINT ORANGE (640 4310);
FORCEPROP 2 LASTPROP $XRERR UNIQUE?
J 0
(400 4310);
DISPLAY 0.638298 (400 4310);
PAINT MONO (400 4310);
DISPLAY INVISIBLE (400 4310);
WIRE 16 -1 (875 4550)(875 4350);
WIRE 16 -1 (875 4350)(1500 4350);
WIRE 16 -1 (550 4350)(875 4350);
FORCEPROP 2 LAST SIG_NAME SMB_DDR_ABC_VPP_SCL_R
J 0
(640 4360);
DISPLAY 0.617021 (640 4360);
PAINT ORANGE (640 4360);
FORCEPROP 2 LASTPROP $XRERR UNIQUE?
J 0
(400 4360);
DISPLAY 0.638298 (400 4360);
PAINT MONO (400 4360);
DISPLAY INVISIBLE (400 4360);
WIRE 16 -1 (1700 900)(2575 900);
FORCEPROP 2 LAST SIG_NAME SMB_DDR_KLM_VPP_SDA
J 0
(1915 910);
DISPLAY 0.617021 (1915 910);
PAINT ORANGE (1915 910);
WIRE 16 -1 (1700 950)(2575 950);
FORCEPROP 2 LAST SIG_NAME SMB_DDR_KLM_VPP_SCL
J 0
(1915 960);
DISPLAY 0.617021 (1915 960);
PAINT ORANGE (1915 960);
WIRE 16 -1 (1700 2150)(2575 2150);
FORCEPROP 2 LAST SIG_NAME SMB_DDR_GHJ_VPP_SCL
J 0
(1915 2160);
DISPLAY 0.617021 (1915 2160);
PAINT ORANGE (1915 2160);
WIRE 16 -1 (1700 2100)(2575 2100);
FORCEPROP 2 LAST SIG_NAME SMB_DDR_GHJ_VPP_SDA
J 0
(1915 2110);
DISPLAY 0.617021 (1915 2110);
PAINT ORANGE (1915 2110);
WIRE 16 -1 (1700 3250)(2550 3250);
WIRE 16 -1 (1700 3300)(2550 3300);
FORCEPROP 2 LAST SIG_NAME SMB_DDR_DEF_VPP_SCL
J 0
(1890 3310);
DISPLAY 0.617021 (1890 3310);
PAINT ORANGE (1890 3310);
WIRE 16 -1 (1275 3500)(1275 3250);
WIRE 16 -1 (1275 3250)(1500 3250);
WIRE 16 -1 (550 3250)(1275 3250);
FORCEPROP 2 LAST SIG_NAME SMB_DDR_DEF_VPP_SDA_R
J 0
(640 3260);
DISPLAY 0.617021 (640 3260);
PAINT ORANGE (640 3260);
FORCEPROP 2 LASTPROP $XRERR UNIQUE?
J 0
(400 3260);
DISPLAY 0.638298 (400 3260);
PAINT MONO (400 3260);
DISPLAY INVISIBLE (400 3260);
WIRE 16 -1 (1225 2350)(1225 2100);
WIRE 16 -1 (1225 2100)(1500 2100);
WIRE 16 -1 (550 2100)(1225 2100);
FORCEPROP 2 LAST SIG_NAME SMB_DDR_GHJ_VPP_SDA_R
J 0
(665 2110);
DISPLAY 0.617021 (665 2110);
PAINT ORANGE (665 2110);
FORCEPROP 2 LASTPROP $XRERR UNIQUE?
J 0
(425 2110);
DISPLAY 0.638298 (425 2110);
PAINT MONO (425 2110);
DISPLAY INVISIBLE (425 2110);
WIRE 16 -1 (875 2150)(1500 2150);
WIRE 16 -1 (875 2350)(875 2150);
WIRE 16 -1 (875 2150)(550 2150);
FORCEPROP 2 LAST SIG_NAME SMB_DDR_GHJ_VPP_SCL_R
J 0
(665 2160);
DISPLAY 0.617021 (665 2160);
PAINT ORANGE (665 2160);
FORCEPROP 2 LASTPROP $XRERR UNIQUE?
J 0
(425 2160);
DISPLAY 0.638298 (425 2160);
PAINT MONO (425 2160);
DISPLAY INVISIBLE (425 2160);
WIRE 16 -1 (925 3300)(1500 3300);
WIRE 16 -1 (925 3500)(925 3300);
WIRE 16 -1 (925 3300)(550 3300);
FORCEPROP 2 LAST SIG_NAME SMB_DDR_DEF_VPP_SCL_R
J 0
(640 3310);
DISPLAY 0.617021 (640 3310);
PAINT ORANGE (640 3310);
FORCEPROP 2 LASTPROP $XRERR UNIQUE?
J 0
(400 3310);
DISPLAY 0.638298 (400 3310);
PAINT MONO (400 3310);
DISPLAY INVISIBLE (400 3310);
WIRE 16 -1 (1225 1150)(1225 900);
WIRE 16 -1 (1225 900)(1500 900);
WIRE 16 -1 (550 900)(1225 900);
FORCEPROP 2 LAST SIG_NAME SMB_DDR_KLM_VPP_SDA_R
J 0
(690 910);
DISPLAY 0.617021 (690 910);
PAINT ORANGE (690 910);
FORCEPROP 2 LASTPROP $XRERR UNIQUE?
J 0
(450 910);
DISPLAY 0.638298 (450 910);
PAINT MONO (450 910);
DISPLAY INVISIBLE (450 910);
WIRE 16 -1 (875 950)(1500 950);
WIRE 16 -1 (875 950)(875 1150);
WIRE 16 -1 (875 950)(550 950);
FORCEPROP 2 LAST SIG_NAME SMB_DDR_KLM_VPP_SCL_R
J 0
(690 960);
DISPLAY 0.617021 (690 960);
PAINT ORANGE (690 960);
FORCEPROP 2 LASTPROP $XRERR UNIQUE?
J 0
(450 960);
DISPLAY 0.638298 (450 960);
PAINT MONO (450 960);
DISPLAY INVISIBLE (450 960);
WIRE 16 -1 (-650 4550)(-650 4300);
WIRE 16 -1 (-650 4300)(-250 4300);
WIRE 16 -1 (-975 4300)(-650 4300);
FORCEPROP 2 LAST SIG_NAME SMB_DDR_ABC_SDA_G
J 2
(-360 4310);
DISPLAY 0.617021 (-360 4310);
PAINT ORANGE (-360 4310);
FORCEPROP 2 LASTPROP $XRERR UNIQUE?
J 0
(-600 4310);
DISPLAY 0.638298 (-600 4310);
PAINT MONO (-600 4310);
DISPLAY INVISIBLE (-600 4310);
WIRE 16 -1 (-1025 4550)(-1025 4350);
WIRE 16 -1 (-1025 4350)(-250 4350);
FORCEPROP 2 LAST SIG_NAME SMB_DDR_ABC_SCL_G
J 2
(-360 4360);
DISPLAY 0.617021 (-360 4360);
PAINT ORANGE (-360 4360);
FORCEPROP 2 LASTPROP $XRERR UNIQUE?
J 0
(-600 4360);
DISPLAY 0.638298 (-600 4360);
PAINT MONO (-600 4360);
DISPLAY INVISIBLE (-600 4360);
WIRE 16 -1 (-1400 4350)(-1025 4350);
WIRE 16 -1 (-1375 4200)(-250 4200);
FORCEPROP 2 LAST SIG_NAME TP_SMB_DDR_ABC_EN
J 0
(-1185 4210);
DISPLAY 0.617021 (-1185 4210);
PAINT ORANGE (-1185 4210);
FORCEPROP 2 LASTPROP $XRERR UNIQUE?
J 0
(-1615 4200);
DISPLAY 0.638298 (-1615 4200);
PAINT MONO (-1615 4200);
DISPLAY INVISIBLE (-1615 4200);
WIRE 16 -1 (-2275 4300)(-1175 4300);
WIRE 16 -1 (-2275 4350)(-1600 4350);
FORCEPROP 2 LAST SIG_NAME SMB_DDR_ABC_SCL_G_R
J 0
(-2210 4360);
DISPLAY 0.617021 (-2210 4360);
PAINT ORANGE (-2210 4360);
WIRE 16 -1 (-675 3500)(-675 3250);
WIRE 16 -1 (-675 3250)(-250 3250);
WIRE 16 -1 (-1075 3250)(-675 3250);
FORCEPROP 2 LAST SIG_NAME SMB_DDR_DEF_SDA_G
J 2
(-360 3260);
DISPLAY 0.617021 (-360 3260);
PAINT ORANGE (-360 3260);
FORCEPROP 2 LASTPROP $XRERR UNIQUE?
J 0
(-600 3260);
DISPLAY 0.638298 (-600 3260);
PAINT MONO (-600 3260);
DISPLAY INVISIBLE (-600 3260);
WIRE 16 -1 (-700 2350)(-700 2100);
WIRE 16 -1 (-700 2100)(-250 2100);
WIRE 16 -1 (-1000 2100)(-700 2100);
FORCEPROP 2 LAST SIG_NAME SMB_DDR_GHJ_SDA_G
J 2
(-360 2110);
DISPLAY 0.617021 (-360 2110);
PAINT ORANGE (-360 2110);
FORCEPROP 2 LASTPROP $XRERR UNIQUE?
J 0
(-600 2110);
DISPLAY 0.638298 (-600 2110);
PAINT MONO (-600 2110);
DISPLAY INVISIBLE (-600 2110);
WIRE 16 -1 (-1075 2350)(-1075 2150);
WIRE 16 -1 (-1075 2150)(-250 2150);
FORCEPROP 2 LAST SIG_NAME SMB_DDR_GHJ_SCL_G
J 2
(-360 2160);
DISPLAY 0.617021 (-360 2160);
PAINT ORANGE (-360 2160);
FORCEPROP 2 LASTPROP $XRERR UNIQUE?
J 0
(-600 2160);
DISPLAY 0.638298 (-600 2160);
PAINT MONO (-600 2160);
DISPLAY INVISIBLE (-600 2160);
WIRE 16 -1 (-1375 2150)(-1075 2150);
WIRE 16 -1 (-1050 3500)(-1050 3300);
WIRE 16 -1 (-1050 3300)(-250 3300);
FORCEPROP 2 LAST SIG_NAME SMB_DDR_DEF_SCL_G
J 2
(-360 3310);
DISPLAY 0.617021 (-360 3310);
PAINT ORANGE (-360 3310);
FORCEPROP 2 LASTPROP $XRERR UNIQUE?
J 0
(-600 3310);
DISPLAY 0.638298 (-600 3310);
PAINT MONO (-600 3310);
DISPLAY INVISIBLE (-600 3310);
WIRE 16 -1 (-1475 3300)(-1050 3300);
WIRE 16 -1 (-1400 3150)(-250 3150);
FORCEPROP 2 LAST SIG_NAME TP_SMB_DDR_DEF_EN
J 0
(-1160 3160);
DISPLAY 0.617021 (-1160 3160);
PAINT ORANGE (-1160 3160);
FORCEPROP 2 LASTPROP $XRERR UNIQUE?
J 0
(-1640 3150);
DISPLAY 0.638298 (-1640 3150);
PAINT MONO (-1640 3150);
DISPLAY INVISIBLE (-1640 3150);
WIRE 16 -1 (-725 1150)(-725 900);
WIRE 16 -1 (-725 900)(-250 900);
FORCEPROP 2 LAST SIG_NAME SMB_DDR_KLM_SDA_G
J 2
(-360 910);
DISPLAY 0.617021 (-360 910);
PAINT ORANGE (-360 910);
FORCEPROP 2 LASTPROP $XRERR UNIQUE?
J 0
(-600 910);
DISPLAY 0.638298 (-600 910);
PAINT MONO (-600 910);
DISPLAY INVISIBLE (-600 910);
WIRE 16 -1 (-725 900)(-1100 900);
WIRE 16 -1 (-1425 2000)(-250 2000);
FORCEPROP 2 LAST SIG_NAME TP_SMB_DDR_GHJ_EN
J 0
(-1210 2010);
DISPLAY 0.617021 (-1210 2010);
PAINT ORANGE (-1210 2010);
FORCEPROP 2 LASTPROP $XRERR UNIQUE?
J 0
(-1665 2000);
DISPLAY 0.638298 (-1665 2000);
PAINT MONO (-1665 2000);
DISPLAY INVISIBLE (-1665 2000);
WIRE 16 -1 (-1450 800)(-250 800);
FORCEPROP 2 LAST SIG_NAME TP_SMB_DDR_KLM_EN
J 0
(-1185 810);
DISPLAY 0.617021 (-1185 810);
PAINT ORANGE (-1185 810);
FORCEPROP 2 LASTPROP $XRERR UNIQUE?
J 0
(-1690 800);
DISPLAY 0.638298 (-1690 800);
PAINT MONO (-1690 800);
DISPLAY INVISIBLE (-1690 800);
WIRE 16 -1 (-1100 1150)(-1100 950);
WIRE 16 -1 (-1100 950)(-250 950);
FORCEPROP 2 LAST SIG_NAME SMB_DDR_KLM_SCL_G
J 2
(-360 960);
DISPLAY 0.617021 (-360 960);
PAINT ORANGE (-360 960);
FORCEPROP 2 LASTPROP $XRERR UNIQUE?
J 0
(-600 960);
DISPLAY 0.638298 (-600 960);
PAINT MONO (-600 960);
DISPLAY INVISIBLE (-600 960);
WIRE 16 -1 (-1475 950)(-1100 950);
WIRE 16 -1 (-2350 950)(-1675 950);
FORCEPROP 2 LAST SIG_NAME SMB_DDR_KLM_SCL_G_R
J 0
(-2325 960);
DISPLAY 0.617021 (-2325 960);
PAINT ORANGE (-2325 960);
WIRE 16 -1 (-2325 2150)(-1575 2150);
FORCEPROP 2 LAST SIG_NAME SMB_DDR_GHJ_SCL_G_R
J 0
(-2250 2160);
DISPLAY 0.617021 (-2250 2160);
PAINT ORANGE (-2250 2160);
WIRE 16 -1 (-2325 2100)(-1200 2100);
FORCEPROP 2 LAST SIG_NAME SMB_DDR_GHJ_SDA_G_R
J 0
(-2250 2110);
DISPLAY 0.617021 (-2250 2110);
PAINT ORANGE (-2250 2110);
WIRE 16 -1 (-2300 3250)(-1275 3250);
WIRE 16 -1 (-2300 3300)(-1675 3300);
FORCEPROP 2 LAST SIG_NAME SMB_DDR_DEF_SCL_G_R
J 0
(-2235 3310);
DISPLAY 0.617021 (-2235 3310);
PAINT ORANGE (-2235 3310);
WIRE 16 -1 (-2350 900)(-1300 900);
FORCEPROP 2 LAST SIG_NAME SMB_DDR_KLM_SDA_G_R
J 0
(-2325 910);
DISPLAY 0.617021 (-2325 910);
PAINT ORANGE (-2325 910);
DOT 1 (-1075 2150);
DOT 1 (1225 4300);
DOT 1 (875 950);
DOT 1 (875 4875);
DOT 1 (875 4350);
DOT 1 (-650 4300);
DOT 1 (-1025 4350);
DOT 1 (-675 3250);
DOT 1 (875 2150);
DOT 1 (-700 2100);
DOT 1 (-975 1475);
DOT 1 (-725 900);
DOT 1 (-1050 3300);
DOT 1 (-1100 950);
DOT 1 (1275 3250);
DOT 1 (925 3825);
DOT 1 (1225 2100);
DOT 1 (875 2675);
DOT 1 (1225 900);
DOT 1 (875 1475);
DOT 1 (925 3300);
DOT 1 (-950 2675);
DOT 1 (-925 3825);
DOT 1 (-900 4875);
FORCENOTE
ROOM=MEM
(3520 675) 0;
DISPLAY LEFT (3520 675);
DISPLAY 1.595745 (3520 675);
PAINT PURPLE (3520 675);
QUIT
